G04 ================== begin FILE IDENTIFICATION RECORD ==================*
G04 Layout Name:  DA0T6MTH8C0_t6m_tray_bp_c_brd_103112_274.brd*
G04 Film Name:    gnd1*
G04 File Format:  Gerber RS274X*
G04 File Origin:  Cadence Allegro 16.3-S048*
G04 Origin Date:  Tue Nov 26 11:26:41 2013*
G04 *
G04 Layer:  DRAWING FORMAT/TITLE_BLOCK*
G04 Layer:  VIA CLASS/GND1*
G04 Layer:  PIN/GND1*
G04 Layer:  MANUFACTURING/PHOTOPLOT_OUTLINE*
G04 Layer:  ETCH/GND1*
G04 Layer:  DRAWING FORMAT/TITLE_DATA_GND1*
G04 *
G04 Offset:    (0.00 0.00)*
G04 Mirror:    No*
G04 Mode:      Negative*
G04 Rotation:  0*
G04 FullContactRelief:  No*
G04 UndefLineWidth:     6.00*
G04 ================== end FILE IDENTIFICATION RECORD ====================*
%FSLAX25Y25*MOIN*%
%IR0*IPPOS*OFA0.00000B0.00000*MIA0B0*SFA1.00000B1.00000*%
%ADD18C,.03*%
%ADD17C,.04*%
%ADD28C,.05*%
%ADD19C,.072*%
%ADD15C,.063*%
%ADD34C,.055*%
%AMMACRO33*
4,1,36,0.0,.0155,
-.002692,.015265,
-.005301,.014565,
-.00775,.013423,
-.009963,.011874,
-.011874,.009963,
-.013423,.00775,
-.014565,.005301,
-.015265,.002692,
-.0155,0.0,
-.015265,-.002692,
-.014565,-.005301,
-.013423,-.00775,
-.011874,-.009963,
-.009963,-.011874,
-.00775,-.013423,
-.005301,-.014565,
-.002692,-.015265,
0.0,-.0155,
.002692,-.015265,
.005301,-.014565,
.00775,-.013423,
.009963,-.011874,
.011874,-.009963,
.013423,-.00775,
.014565,-.005301,
.015265,-.002692,
.0155,0.0,
.015265,.002692,
.014565,.005301,
.013423,.00775,
.011874,.009963,
.009963,.011874,
.00775,.013423,
.005301,.014565,
.002692,.015265,
0.0,.0155,
0.0*
%
%ADD33MACRO33*%
%ADD14C,.073*%
%ADD30C,.093*%
%ADD11C,.066*%
%AMMACRO37*
4,1,36,0.0,.004,
.000695,.003939,
.001368,.003759,
.002,.003464,
.002571,.003064,
.003064,.002571,
.003464,.002,
.003759,.001368,
.003939,.000695,
.004,0.0,
.003939,-.000695,
.003759,-.001368,
.003464,-.002,
.003064,-.002571,
.002571,-.003064,
.002,-.003464,
.001368,-.003759,
.000695,-.003939,
0.0,-.004,
-.000695,-.003939,
-.001368,-.003759,
-.002,-.003464,
-.002571,-.003064,
-.003064,-.002571,
-.003464,-.002,
-.003759,-.001368,
-.003939,-.000695,
-.004,0.0,
-.003939,.000695,
-.003759,.001368,
-.003464,.002,
-.003064,.002571,
-.002571,.003064,
-.002,.003464,
-.001368,.003759,
-.000695,.003939,
0.0,.004,
180.*
%
%ADD37MACRO37*%
%AMMACRO24*
4,1,36,0.0,.004,
.000695,.003939,
.001368,.003759,
.002,.003464,
.002571,.003064,
.003064,.002571,
.003464,.002,
.003759,.001368,
.003939,.000695,
.004,0.0,
.003939,-.000695,
.003759,-.001368,
.003464,-.002,
.003064,-.002571,
.002571,-.003064,
.002,-.003464,
.001368,-.003759,
.000695,-.003939,
0.0,-.004,
-.000695,-.003939,
-.001368,-.003759,
-.002,-.003464,
-.002571,-.003064,
-.003064,-.002571,
-.003464,-.002,
-.003759,-.001368,
-.003939,-.000695,
-.004,0.0,
-.003939,.000695,
-.003759,.001368,
-.003464,.002,
-.003064,.002571,
-.002571,.003064,
-.002,.003464,
-.001368,.003759,
-.000695,.003939,
0.0,.004,
270.*
%
%ADD24MACRO24*%
%ADD20C,.058*%
%AMMACRO29*
4,1,36,0.0,.0175,
-.003039,.017234,
-.005985,.016445,
-.00875,.015155,
-.011249,.013406,
-.013406,.011249,
-.015155,.00875,
-.016445,.005985,
-.017234,.003039,
-.0175,0.0,
-.017234,-.003039,
-.016445,-.005985,
-.015155,-.00875,
-.013406,-.011249,
-.011249,-.013406,
-.00875,-.015155,
-.005985,-.016445,
-.003039,-.017234,
0.0,-.0175,
.003039,-.017234,
.005985,-.016445,
.00875,-.015155,
.011249,-.013406,
.013406,-.011249,
.015155,-.00875,
.016445,-.005985,
.017234,-.003039,
.0175,0.0,
.017234,.003039,
.016445,.005985,
.015155,.00875,
.013406,.011249,
.011249,.013406,
.00875,.015155,
.005985,.016445,
.003039,.017234,
0.0,.0175,
0.0*
%
%ADD29MACRO29*%
%AMMACRO22*
4,1,36,0.0,.009,
.001563,.008863,
.003078,.008457,
.0045,.007794,
.005785,.006894,
.006894,.005785,
.007794,.0045,
.008457,.003078,
.008863,.001563,
.009,0.0,
.008863,-.001563,
.008457,-.003078,
.007794,-.0045,
.006894,-.005785,
.005785,-.006894,
.0045,-.007794,
.003078,-.008457,
.001563,-.008863,
0.0,-.009,
-.001563,-.008863,
-.003078,-.008457,
-.0045,-.007794,
-.005785,-.006894,
-.006894,-.005785,
-.007794,-.0045,
-.008457,-.003078,
-.008863,-.001563,
-.009,0.0,
-.008863,.001563,
-.008457,.003078,
-.007794,.0045,
-.006894,.005785,
-.005785,.006894,
-.0045,.007794,
-.003078,.008457,
-.001563,.008863,
0.0,.009,
0.0*
%
%ADD22MACRO22*%
%AMMACRO26*
4,1,36,0.0,.014,
-.002431,.013787,
-.004788,.013156,
-.007,.012124,
-.008999,.010725,
-.010725,.008999,
-.012124,.007,
-.013156,.004788,
-.013787,.002431,
-.014,0.0,
-.013787,-.002431,
-.013156,-.004788,
-.012124,-.007,
-.010725,-.008999,
-.008999,-.010725,
-.007,-.012124,
-.004788,-.013156,
-.002431,-.013787,
0.0,-.014,
.002431,-.013787,
.004788,-.013156,
.007,-.012124,
.008999,-.010725,
.010725,-.008999,
.012124,-.007,
.013156,-.004788,
.013787,-.002431,
.014,0.0,
.013787,.002431,
.013156,.004788,
.012124,.007,
.010725,.008999,
.008999,.010725,
.007,.012124,
.004788,.013156,
.002431,.013787,
0.0,.014,
0.0*
%
%ADD26MACRO26*%
%AMMACRO35*
4,1,15,.04161,.02393,
.045133,.016341,
.047285,.008255,
.048,-.000081,
.047257,-.008415,
.045078,-.016493,
.04161,-.02393,
.04671,-.02903,
.051041,-.020478,
.053822,-.011304,
.054967,-.001786,
.054442,.007786,
.052263,.017122,
.048496,.025937,
.04671,.02903,
.04161,.02393,
180.*
4,1,15,.02393,-.04161,
.016341,-.045133,
.008255,-.047285,
-.000081,-.048,
-.008415,-.047257,
-.016493,-.045078,
-.02393,-.04161,
-.02903,-.04671,
-.020478,-.051041,
-.011304,-.053822,
-.001786,-.054967,
.007786,-.054442,
.017122,-.052263,
.025937,-.048496,
.02903,-.04671,
.02393,-.04161,
180.*
4,1,15,-.04161,-.02393,
-.045133,-.016341,
-.047285,-.008255,
-.048,.000081,
-.047257,.008415,
-.045078,.016493,
-.04161,.02393,
-.04671,.02903,
-.051041,.020478,
-.053822,.011304,
-.054967,.001786,
-.054442,-.007786,
-.052263,-.017122,
-.048496,-.025937,
-.04671,-.02903,
-.04161,-.02393,
180.*
4,1,15,-.02393,.04161,
-.016341,.045133,
-.008255,.047285,
.000081,.048,
.008415,.047257,
.016493,.045078,
.02393,.04161,
.02903,.04671,
.020478,.051041,
.011304,.053822,
.001786,.054967,
-.007786,.054442,
-.017122,.052263,
-.025937,.048496,
-.02903,.04671,
-.02393,.04161,
180.*
%
%ADD35MACRO35*%
%AMMACRO31*
4,1,36,0.0,.0195,
-.003386,.019204,
-.006669,.018324,
-.00975,.016887,
-.012534,.014938,
-.014938,.012534,
-.016887,.00975,
-.018324,.006669,
-.019204,.003386,
-.0195,0.0,
-.019204,-.003386,
-.018324,-.006669,
-.016887,-.00975,
-.014938,-.012534,
-.012534,-.014938,
-.00975,-.016887,
-.006669,-.018324,
-.003386,-.019204,
0.0,-.0195,
.003386,-.019204,
.006669,-.018324,
.00975,-.016887,
.012534,-.014938,
.014938,-.012534,
.016887,-.00975,
.018324,-.006669,
.019204,-.003386,
.0195,0.0,
.019204,.003386,
.018324,.006669,
.016887,.00975,
.014938,.012534,
.012534,.014938,
.00975,.016887,
.006669,.018324,
.003386,.019204,
0.0,.0195,
0.0*
%
%ADD31MACRO31*%
%AMMACRO38*
4,1,16,.04853,.03085,
.05315,.021954,
.056155,.012391,
.057453,.002452,
.057006,-.007562,
.054827,-.017346,
.050982,-.026603,
.04853,-.03085,
.05358,-.0359,
.059,-.026051,
.062627,-.01541,
.064352,-.0043,
.064121,.00694,
.061942,.017969,
.05788,.028452,
.05358,.0359,
.04853,.03085,
0.0*
4,1,16,.03085,-.04853,
.021954,-.05315,
.012391,-.056155,
.002452,-.057453,
-.007562,-.057006,
-.017346,-.054827,
-.026603,-.050982,
-.03085,-.04853,
-.0359,-.05358,
-.026051,-.059,
-.01541,-.062627,
-.0043,-.064352,
.00694,-.064121,
.017969,-.061942,
.028452,-.05788,
.0359,-.05358,
.03085,-.04853,
0.0*
4,1,16,-.04853,-.03085,
-.05315,-.021954,
-.056155,-.012391,
-.057453,-.002452,
-.057006,.007562,
-.054827,.017346,
-.050982,.026603,
-.04853,.03085,
-.05358,.0359,
-.059,.026051,
-.062627,.01541,
-.064352,.0043,
-.064121,-.00694,
-.061942,-.017969,
-.05788,-.028452,
-.05358,-.0359,
-.04853,-.03085,
0.0*
4,1,16,-.03085,.04853,
-.021954,.05315,
-.012391,.056155,
-.002452,.057453,
.007562,.057006,
.017346,.054827,
.026603,.050982,
.03085,.04853,
.0359,.05358,
.026051,.059,
.01541,.062627,
.0043,.064352,
-.00694,.064121,
-.017969,.061942,
-.028452,.05788,
-.0359,.05358,
-.03085,.04853,
0.0*
%
%ADD38MACRO38*%
%AMMACRO25*
4,1,16,.07401,.04573,
.080827,.032184,
.085187,.017659,
.08696,.002598,
.08609,-.012541,
.082604,-.0273,
.076608,-.04123,
.07401,-.04573,
.07909,-.0508,
.08671,-.036294,
.091695,-.020686,
.093894,-.004449,
.09324,.011923,
.089753,.027933,
.083539,.043094,
.07909,.0508,
.07401,.04573,
0.0*
4,1,16,.04573,-.07401,
.032184,-.080827,
.017659,-.085187,
.002598,-.08696,
-.012541,-.08609,
-.0273,-.082604,
-.04123,-.076608,
-.04573,-.07401,
-.0508,-.07909,
-.036294,-.08671,
-.020686,-.091695,
-.004449,-.093894,
.011923,-.09324,
.027933,-.089753,
.043094,-.083539,
.0508,-.07909,
.04573,-.07401,
0.0*
4,1,16,-.07401,-.04573,
-.080827,-.032184,
-.085187,-.017659,
-.08696,-.002598,
-.08609,.012541,
-.082604,.0273,
-.076608,.04123,
-.07401,.04573,
-.07909,.0508,
-.08671,.036294,
-.091695,.020686,
-.093894,.004449,
-.09324,-.011923,
-.089753,-.027933,
-.083539,-.043094,
-.07909,-.0508,
-.07401,-.04573,
0.0*
4,1,16,-.04573,.07401,
-.032184,.080827,
-.017659,.085187,
-.002598,.08696,
.012541,.08609,
.0273,.082604,
.04123,.076608,
.04573,.07401,
.0508,.07909,
.036294,.08671,
.020686,.091695,
.004449,.093894,
-.011923,.09324,
-.027933,.089753,
-.043094,.083539,
-.0508,.07909,
-.04573,.07401,
0.0*
%
%ADD25MACRO25*%
%AMMACRO21*
4,1,15,.02364,.01304,
.025545,.008737,
.026674,.004168,
.026993,-.000527,
.026491,-.005206,
.025185,-.009727,
.02364,-.01304,
.02875,-.01815,
.031465,-.012882,
.033224,-.007222,
.033973,-.001343,
.03369,.004576,
.032384,.010357,
.030093,.015823,
.02875,.01815,
.02364,.01304,
90.*
4,1,15,.01304,-.02364,
.008737,-.025545,
.004168,-.026674,
-.000527,-.026993,
-.005206,-.026491,
-.009727,-.025185,
-.01304,-.02364,
-.01815,-.02875,
-.012882,-.031465,
-.007222,-.033224,
-.001343,-.033973,
.004576,-.03369,
.010357,-.032384,
.015823,-.030093,
.01815,-.02875,
.01304,-.02364,
90.*
4,1,15,-.02364,-.01304,
-.025545,-.008737,
-.026674,-.004168,
-.026993,.000527,
-.026491,.005206,
-.025185,.009727,
-.02364,.01304,
-.02875,.01815,
-.031465,.012882,
-.033224,.007222,
-.033973,.001343,
-.03369,-.004576,
-.032384,-.010357,
-.030093,-.015823,
-.02875,-.01815,
-.02364,-.01304,
90.*
4,1,15,-.01304,.02364,
-.008737,.025545,
-.004168,.026674,
.000527,.026993,
.005206,.026491,
.009727,.025185,
.01304,.02364,
.01815,.02875,
.012882,.031465,
.007222,.033224,
.001343,.033973,
-.004576,.03369,
-.010357,.032384,
-.015823,.030093,
-.01815,.02875,
-.01304,.02364,
90.*
%
%ADD21MACRO21*%
%AMMACRO16*
4,1,16,.02548,.01487,
.027675,.01022,
.029029,.005259,
.029501,.000138,
.029077,-.004987,
.027769,-.009961,
.025618,-.014631,
.02548,-.01487,
.03056,-.01996,
.033562,-.01435,
.035544,-.008304,
.036446,-.002006,
.03624,.004353,
.034934,.01058,
.032566,.016486,
.03056,.01996,
.02548,.01487,
90.*
4,1,16,.01487,-.02548,
.01022,-.027675,
.005259,-.029029,
.000138,-.029501,
-.004987,-.029077,
-.009961,-.027769,
-.014631,-.025618,
-.01487,-.02548,
-.01996,-.03056,
-.01435,-.033562,
-.008304,-.035544,
-.002006,-.036446,
.004353,-.03624,
.01058,-.034934,
.016486,-.032566,
.01996,-.03056,
.01487,-.02548,
90.*
4,1,16,-.02548,-.01487,
-.027675,-.01022,
-.029029,-.005259,
-.029501,-.000138,
-.029077,.004987,
-.027769,.009961,
-.025618,.014631,
-.02548,.01487,
-.03056,.01996,
-.033562,.01435,
-.035544,.008304,
-.036446,.002006,
-.03624,-.004353,
-.034934,-.01058,
-.032566,-.016486,
-.03056,-.01996,
-.02548,-.01487,
90.*
4,1,16,-.01487,.02548,
-.01022,.027675,
-.005259,.029029,
-.000138,.029501,
.004987,.029077,
.009961,.027769,
.014631,.025618,
.01487,.02548,
.01996,.03056,
.01435,.033562,
.008304,.035544,
.002006,.036446,
-.004353,.03624,
-.01058,.034934,
-.016486,.032566,
-.01996,.03056,
-.01487,.02548,
90.*
%
%ADD16MACRO16*%
%AMMACRO39*
4,1,17,.03237,.02176,
.035657,.015808,
.03786,.009377,
.038913,.00266,
.038784,-.004138,
.037476,-.01081,
.03503,-.017153,
.03237,-.02176,
.03739,-.02679,
.041474,-.01989,
.044298,-.012386,
.045776,-.004506,
.045863,.003511,
.044556,.011422,
.041896,.018986,
.037962,.025972,
.03739,.02679,
.03237,.02176,
0.0*
4,1,17,.02176,-.03237,
.015808,-.035657,
.009377,-.03786,
.00266,-.038913,
-.004138,-.038784,
-.01081,-.037476,
-.017153,-.03503,
-.02176,-.03237,
-.02679,-.03739,
-.01989,-.041474,
-.012386,-.044298,
-.004506,-.045776,
.003511,-.045863,
.011422,-.044556,
.018986,-.041896,
.025972,-.037962,
.02679,-.03739,
.02176,-.03237,
0.0*
4,1,17,-.03237,-.02176,
-.035657,-.015808,
-.03786,-.009377,
-.038913,-.00266,
-.038784,.004138,
-.037476,.01081,
-.03503,.017153,
-.03237,.02176,
-.03739,.02679,
-.041474,.01989,
-.044298,.012386,
-.045776,.004506,
-.045863,-.003511,
-.044556,-.011422,
-.041896,-.018986,
-.037962,-.025972,
-.03739,-.02679,
-.03237,-.02176,
0.0*
4,1,17,-.02176,.03237,
-.015808,.035657,
-.009377,.03786,
-.00266,.038913,
.004138,.038784,
.01081,.037476,
.017153,.03503,
.02176,.03237,
.02679,.03739,
.01989,.041474,
.012386,.044298,
.004506,.045776,
-.003511,.045863,
-.011422,.044556,
-.018986,.041896,
-.025972,.037962,
-.02679,.03739,
-.02176,.03237,
0.0*
%
%ADD39MACRO39*%
%ADD27C,.115*%
%AMMACRO10*
4,1,36,0.0,.01,
-.001736,.009848,
-.00342,.009397,
-.005,.00866,
-.006428,.00766,
-.00766,.006428,
-.00866,.005,
-.009397,.00342,
-.009848,.001736,
-.01,0.0,
-.009848,-.001736,
-.009397,-.00342,
-.00866,-.005,
-.00766,-.006428,
-.006428,-.00766,
-.005,-.00866,
-.00342,-.009397,
-.001736,-.009848,
0.0,-.01,
.001736,-.009848,
.00342,-.009397,
.005,-.00866,
.006428,-.00766,
.00766,-.006428,
.00866,-.005,
.009397,-.00342,
.009848,-.001736,
.01,0.0,
.009848,.001736,
.009397,.00342,
.00866,.005,
.00766,.006428,
.006428,.00766,
.005,.00866,
.00342,.009397,
.001736,.009848,
0.0,.01,
180.*
%
%ADD10MACRO10*%
%ADD12C,.172*%
%ADD36C,.158*%
%ADD32O,.068X.093*%
%ADD13C,.168*%
%AMMACRO23*
4,1,36,0.0,.004,
.000695,.003939,
.001368,.003759,
.002,.003464,
.002571,.003064,
.003064,.002571,
.003464,.002,
.003759,.001368,
.003939,.000695,
.004,0.0,
.003939,-.000695,
.003759,-.001368,
.003464,-.002,
.003064,-.002571,
.002571,-.003064,
.002,-.003464,
.001368,-.003759,
.000695,-.003939,
0.0,-.004,
-.000695,-.003939,
-.001368,-.003759,
-.002,-.003464,
-.002571,-.003064,
-.003064,-.002571,
-.003464,-.002,
-.003759,-.001368,
-.003939,-.000695,
-.004,0.0,
-.003939,.000695,
-.003759,.001368,
-.003464,.002,
-.003064,.002571,
-.002571,.003064,
-.002,.003464,
-.001368,.003759,
-.000695,.003939,
0.0,.004,
0.0*
%
%ADD23MACRO23*%
%ADD40C,.006*%
%ADD41R,.057X.111*%
%ADD43C,.09612*%
%ADD49C,.07608*%
%ADD44C,.09606*%
%ADD45C,.1601*%
%ADD46C,.16024*%
%ADD47C,.11706*%
%ADD42R,.072X.096*%
%ADD50C,.18206*%
%ADD48C,.11708*%
G75*
%LPD*%
G75*
G36*
G01X-471400Y-391900D02*
X2244200D01*
Y1528800D01*
X-471400D01*
Y-391900D01*
G37*
%LPC*%
G75*
G36*
G01X1393661Y203980D02*
G02X1395594Y202047I0J-1933D01*
G01Y200000D01*
G03X1401535Y194059I5941J0D01*
G01X1460591D01*
G03X1466532Y200000I0J5941D01*
G01Y202047D01*
G02X1468465Y203980I1933J0D01*
G01X1495827D01*
X1496748Y203797D01*
X1497363Y203386D01*
X1497779Y202763D01*
X1497973Y201835D01*
X1498412Y199951D01*
X1499704Y198060D01*
X1501632Y196788D01*
X1503703Y196382D01*
X1675630D01*
G02X1681500Y190512I0J-5870D01*
G01Y165890D01*
G02X1681000Y165390I-500J0D01*
G01X1675236D01*
G03X1671264Y161417I0J-3972D01*
G01Y125984D01*
G03X1675236Y122012I3972J0D01*
G01X1681000D01*
G02X1681500Y121512I0J-500D01*
G01Y43307D01*
G03X1685472Y39335I3972J0D01*
G01X1685724D01*
G02X1686224Y38835I0J-500D01*
G01Y7874D01*
G02X1680354Y2004I-5870J0D01*
G01X7874D01*
G02X2004Y7874I0J5870D01*
G01Y182900D01*
G02X2504Y183400I500J0D01*
G01X38638D01*
G02X39138Y182900I0J-500D01*
G01Y167913D01*
G03X45902I3382J0D01*
G01Y177500D01*
G02X46402Y178000I500J0D01*
G01X47371D01*
X47471Y178100D01*
X71987D01*
X72087Y178000D01*
X198113D01*
X198213Y178100D01*
X202535D01*
G02X203035Y177600I0J-500D01*
G01Y170551D01*
G03X208976Y164610I5941J0D01*
G01X216850D01*
G03X222791Y170551I0J5941D01*
G01Y198110D01*
G02X228661Y203980I5870J0D01*
G01X372887D01*
G02X374700Y202047I-124J-1933D01*
G01Y200000D01*
G03X380637Y194063I5937J0D01*
G01X381965D01*
G03X382165Y194059I219J5937D01*
G01X441220D01*
G03X447161Y200000I0J5941D01*
G01Y202047D01*
G02X449094Y203980I1933J0D01*
G01X523583D01*
G02X525516Y202047I0J-1933D01*
G01Y200000D01*
G03X531457Y194059I5941J0D01*
G01X590512D01*
G03X596453Y200000I0J5941D01*
G01Y202047D01*
G02X598386Y203980I1933J0D01*
G01X625748D01*
X626669Y203797D01*
X627284Y203386D01*
X627700Y202763D01*
X627894Y201835D01*
X628333Y199951D01*
X629625Y198060D01*
X631553Y196788D01*
X633624Y196382D01*
X799368D01*
X801439Y196788D01*
X803367Y198060D01*
X804659Y199951D01*
X805098Y201835D01*
X805292Y202763D01*
X805708Y203386D01*
X806323Y203797D01*
X807244Y203980D01*
X1244370D01*
G02X1246303Y202047I0J-1933D01*
G01Y200000D01*
G03X1252244Y194059I5941J0D01*
G01X1311299D01*
G03X1317240Y200000I0J5941D01*
G01Y202047D01*
G02X1319173Y203980I1933J0D01*
G01X1393661D01*
G37*
%LPD*%
G75*
G36*
G01X792554Y30690D02*
Y18504D01*
G02X774768I-8893J0D01*
G01Y30690D01*
G03X774164Y32095I-1934J1D01*
G02X771203Y36159I9497J10030D01*
G01X771166Y36236D01*
X770661Y36741D01*
Y37455D01*
X770633Y37536D01*
G02Y46716I13028J4590D01*
G01X770661Y46797D01*
Y47512D01*
X771167Y48018D01*
X771204Y48095D01*
G02X777692Y54583I12457J-5969D01*
G01X777769Y54620D01*
X778276Y55127D01*
X778993D01*
X779073Y55155D01*
G02X788249I4588J-13029D01*
G01X788329Y55127D01*
X789046D01*
X789553Y54620D01*
X789630Y54583D01*
G02X796118Y48095I-5969J-12457D01*
G01X796155Y48018D01*
X796661Y47512D01*
Y46797D01*
X796689Y46716D01*
G02Y37536I-13028J-4590D01*
G01X796661Y37455D01*
Y36741D01*
X796156Y36236D01*
X796119Y36159D01*
G02X793158Y32095I-12458J5966D01*
G03X792554Y30690I1330J-1404D01*
G37*
G36*
G01X1089159Y36155D02*
X1089122Y36232D01*
X1088614Y36740D01*
Y37458D01*
X1088586Y37539D01*
G02Y46714I13029J4588D01*
G01X1088614Y46794D01*
Y47511D01*
X1089121Y48018D01*
X1089158Y48095D01*
G02X1095646Y54583I12457J-5969D01*
G01X1095723Y54620D01*
X1096229Y55126D01*
X1096944D01*
X1097024Y55154D01*
G02X1106206I4591J-13028D01*
G01X1106286Y55126D01*
X1106999D01*
X1107503Y54622D01*
X1107580Y54585D01*
G02X1114074Y48091I-5965J-12459D01*
G01X1114111Y48014D01*
X1114614Y47511D01*
Y46800D01*
X1114642Y46719D01*
G02Y37533I-13027J-4593D01*
G01X1114614Y37453D01*
Y36740D01*
X1114110Y36236D01*
X1114073Y36159D01*
G02X1111112Y32095I-12458J5966D01*
G03X1110508Y30690I1330J-1404D01*
G01Y18504D01*
G02X1097644Y10547I-8893J0D01*
G02X1093930Y14030I3970J7955D01*
G02X1092722Y18504I7685J4475D01*
G01Y30690D01*
G03X1092118Y32095I-1934J1D01*
G02X1089159Y36155I9498J10030D01*
G37*
G36*
G01X5258Y131828D02*
X5221Y131905D01*
X4716Y132410D01*
Y133124D01*
X4688Y133205D01*
G02Y142385I13028J4590D01*
G01X4716Y142466D01*
Y143181D01*
X5222Y143687D01*
X5259Y143764D01*
G02X11747Y150252I12457J-5969D01*
G01X11824Y150289D01*
X12331Y150796D01*
X13048D01*
X13128Y150824D01*
G02X22304I4588J-13029D01*
G01X22384Y150796D01*
X23101D01*
X23608Y150289D01*
X23685Y150252D01*
G02X30173Y143764I-5969J-12457D01*
G01X30210Y143687D01*
X30716Y143181D01*
Y142466D01*
X30744Y142385D01*
G02Y133205I-13028J-4590D01*
G01X30716Y133124D01*
Y132410D01*
X30211Y131905D01*
X30174Y131828D01*
G02X27213Y127764I-12458J5966D01*
G03X26608Y126359I1330J-1405D01*
G01Y114173D01*
G02X8824I-8892J0D01*
G01Y126359D01*
G03X8219Y127764I-1935J0D01*
G02X5258Y131828I9497J10030D01*
G37*
G36*
G01X323106Y175572D02*
Y163386D01*
G02X305320I-8893J0D01*
G01Y175572D01*
G03X304716Y176977I-1934J1D01*
G02X301755Y181041I9497J10030D01*
G01X301718Y181118D01*
X301212Y181624D01*
Y182340D01*
X301184Y182421D01*
G02Y191596I13029J4587D01*
G01X301212Y191676D01*
Y192395D01*
X301721Y192904D01*
X301758Y192981D01*
G02X308241Y199464I12455J-5972D01*
G01X308318Y199501D01*
X308827Y200010D01*
X309547D01*
X309628Y200038D01*
G02X318798I4585J-13030D01*
G01X318879Y200010D01*
X319597D01*
X320105Y199502D01*
X320182Y199465D01*
G02X326670Y192977I-5969J-12457D01*
G01X326707Y192900D01*
X327212Y192395D01*
Y191682D01*
X327240Y191601D01*
G02Y182415I-13027J-4593D01*
G01X327212Y182335D01*
Y181624D01*
X326710Y181122D01*
X326673Y181044D01*
G02X323710Y176977I-12460J5965D01*
G03X323106Y175572I1330J-1404D01*
G37*
G36*
G01X820053Y199464D02*
X820130Y199501D01*
X820638Y200009D01*
X821356D01*
X821436Y200037D01*
G02X830612I4588J-13029D01*
G01X830692Y200009D01*
X831408D01*
X831914Y199503D01*
X831991Y199466D01*
G02X838482Y192975I-5967J-12458D01*
G01X838519Y192898D01*
X839023Y192394D01*
Y191682D01*
X839051Y191601D01*
G02Y182415I-13027J-4593D01*
G01X839023Y182335D01*
Y181623D01*
X838520Y181120D01*
X838483Y181042D01*
G02X835521Y176977I-12459J5966D01*
G03X834916Y175572I1330J-1405D01*
G01Y163386D01*
G02X817131I-8892J0D01*
G01X817132Y175572D01*
G03X816527Y176977I-1935J0D01*
G02X813567Y181039I9498J10030D01*
G01X813530Y181116D01*
X813023Y181623D01*
Y182340D01*
X812995Y182421D01*
G02Y191596I13029J4587D01*
G01X813023Y191676D01*
Y192394D01*
X813531Y192902D01*
X813568Y192979D01*
G02X820053Y199464I12456J-5971D01*
G37*
G36*
G01X1178321D02*
X1178398Y199501D01*
X1178906Y200009D01*
X1179624D01*
X1179704Y200037D01*
G02X1188880I4588J-13029D01*
G01X1188960Y200009D01*
X1189676D01*
X1190182Y199503D01*
X1190259Y199466D01*
G02X1196750Y192975I-5967J-12458D01*
G01X1196787Y192898D01*
X1197291Y192394D01*
Y191682D01*
X1197319Y191601D01*
G02Y182415I-13027J-4593D01*
G01X1197291Y182335D01*
Y181623D01*
X1196788Y181120D01*
X1196751Y181042D01*
G02X1193789Y176977I-12459J5966D01*
G03X1193184Y175572I1330J-1405D01*
G01Y163386D01*
G02X1175400I-8892J0D01*
G01Y175572D01*
G03X1174795Y176977I-1935J0D01*
G02X1171835Y181039I9498J10030D01*
G01X1171798Y181116D01*
X1171291Y181623D01*
Y182340D01*
X1171263Y182421D01*
G02Y191596I13029J4587D01*
G01X1171291Y191676D01*
Y192394D01*
X1171799Y192902D01*
X1171836Y192979D01*
G02X1178321Y199464I12456J-5971D01*
G37*
G36*
G01X430493Y61456D02*
G02X434096Y57853I0J-3603D01*
G01Y55353D01*
G02X427090I-3503J0D01*
G01Y58053D01*
G02X430493Y61456I3403J0D01*
G37*
G36*
G01X579785D02*
G02X583388Y57854I1J-3602D01*
G01Y55354D01*
G02X576382I-3503J0D01*
G01Y58054D01*
G02X579784Y61456I3402J0D01*
G01X579785D01*
G37*
G36*
G01X1300572D02*
G02X1304174Y57854I0J-3602D01*
G01Y55354D01*
G02X1297169I-3503J0D01*
G01X1297170Y58054D01*
G02X1300572Y61456I3402J0D01*
G37*
G36*
G01X1449864Y61455D02*
G02X1453466Y57853I0J-3602D01*
G01Y55353D01*
G02X1446462I-3502J0D01*
G01Y58053D01*
G02X1449864Y61455I3402J0D01*
G37*
G36*
G01X654474Y16390D02*
X654574D01*
Y16590D01*
X659574D01*
Y5296D01*
X654474D01*
Y16390D01*
G37*
G36*
G01X685970D02*
X686070D01*
Y16590D01*
X691070D01*
Y5296D01*
X685970D01*
Y16390D01*
G37*
G36*
G01X1524553D02*
X1524653D01*
Y16590D01*
X1529653D01*
Y5296D01*
X1524553D01*
Y16390D01*
G37*
G36*
G01X1556049D02*
X1556149D01*
Y16590D01*
X1561149D01*
Y5296D01*
X1556049D01*
Y16390D01*
G37*
G36*
G01X646600Y21328D02*
X646700D01*
Y21528D01*
X651700D01*
Y10628D01*
X646600D01*
Y21328D01*
G37*
G36*
G01X678096D02*
X678196D01*
Y21528D01*
X683196D01*
Y10628D01*
X678096D01*
Y21328D01*
G37*
G36*
G01X1516679D02*
X1516779D01*
Y21528D01*
X1521779D01*
Y10628D01*
X1516679D01*
Y21328D01*
G37*
G36*
G01X1548175D02*
X1548275D01*
Y21528D01*
X1553275D01*
Y10628D01*
X1548175D01*
Y21328D01*
G37*
G36*
G01X522472Y22580D02*
X524128D01*
X525300Y21408D01*
Y14752D01*
X524128Y13580D01*
X522472D01*
X521300Y14752D01*
Y21408D01*
X522472Y22580D01*
G37*
G36*
G01X1392551D02*
X1394207D01*
X1395379Y21408D01*
Y14752D01*
X1394207Y13580D01*
X1392551D01*
X1391379Y14752D01*
Y21408D01*
X1392551Y22580D01*
G37*
G36*
G01X399703Y23960D02*
X406359D01*
X407531Y22788D01*
Y21132D01*
X406359Y19960D01*
X399703D01*
X398531Y21132D01*
Y22788D01*
X399703Y23960D01*
G37*
G36*
G01X1269782D02*
X1276438D01*
X1277610Y22788D01*
Y21132D01*
X1276438Y19960D01*
X1269782D01*
X1268610Y21132D01*
Y22788D01*
X1269782Y23960D01*
G37*
G36*
G01X567893Y24500D02*
X574549D01*
X575721Y23328D01*
Y21672D01*
X574549Y20500D01*
X567893D01*
X566721Y21672D01*
Y23328D01*
X567893Y24500D01*
G37*
G36*
G01X1437972D02*
X1444628D01*
X1445800Y23328D01*
Y21672D01*
X1444628Y20500D01*
X1437972D01*
X1436800Y21672D01*
Y23328D01*
X1437972Y24500D01*
G37*
G36*
G01X654474Y32926D02*
X654574D01*
Y33126D01*
X659574D01*
Y21832D01*
X654474D01*
Y32926D01*
G37*
G36*
G01X670222D02*
X670322D01*
Y33126D01*
X675322D01*
Y21832D01*
X670222D01*
Y32926D01*
G37*
G36*
G01X685970D02*
X686070D01*
Y33126D01*
X691070D01*
Y21832D01*
X685970D01*
Y32926D01*
G37*
G36*
G01X1524553D02*
X1524653D01*
Y33126D01*
X1529653D01*
Y21832D01*
X1524553D01*
Y32926D01*
G37*
G36*
G01X1540301D02*
X1540401D01*
Y33126D01*
X1545401D01*
Y21832D01*
X1540301D01*
Y32926D01*
G37*
G36*
G01X1556049D02*
X1556149D01*
Y33126D01*
X1561149D01*
Y21832D01*
X1556049D01*
Y32926D01*
G37*
G36*
G01X646600Y37864D02*
X646700D01*
Y38064D01*
X651700D01*
Y27164D01*
X646600D01*
Y37864D01*
G37*
G36*
G01X662348D02*
X662448D01*
Y38064D01*
X667448D01*
Y27164D01*
X662348D01*
Y37864D01*
G37*
G36*
G01X678096D02*
X678196D01*
Y38064D01*
X683196D01*
Y27164D01*
X678096D01*
Y37864D01*
G37*
G36*
G01X1516679D02*
X1516779D01*
Y38064D01*
X1521779D01*
Y27164D01*
X1516679D01*
Y37864D01*
G37*
G36*
G01X1532427D02*
X1532527D01*
Y38064D01*
X1537527D01*
Y27164D01*
X1532427D01*
Y37864D01*
G37*
G36*
G01X1548175D02*
X1548275D01*
Y38064D01*
X1553275D01*
Y27164D01*
X1548175D01*
Y37864D01*
G37*
G36*
G01X447052Y38200D02*
X454308D01*
X455480Y37028D01*
Y35372D01*
X454308Y34200D01*
X447052D01*
X445880Y35372D01*
Y37028D01*
X447052Y38200D01*
G37*
G36*
G01X1317131D02*
X1324387D01*
X1325559Y37028D01*
Y35372D01*
X1324387Y34200D01*
X1317131D01*
X1315959Y35372D01*
Y37028D01*
X1317131Y38200D01*
G37*
G36*
G01X654474Y49462D02*
X654574D01*
Y49662D01*
X659574D01*
Y38368D01*
X654474D01*
Y49462D01*
G37*
G36*
G01X670222D02*
X670322D01*
Y49662D01*
X675322D01*
Y38368D01*
X670222D01*
Y49462D01*
G37*
G36*
G01X685970D02*
X686070D01*
Y49662D01*
X691070D01*
Y38368D01*
X685970D01*
Y49462D01*
G37*
G36*
G01X1524553D02*
X1524653D01*
Y49662D01*
X1529653D01*
Y38368D01*
X1524553D01*
Y49462D01*
G37*
G36*
G01X1540301D02*
X1540401D01*
Y49662D01*
X1545401D01*
Y38368D01*
X1540301D01*
Y49462D01*
G37*
G36*
G01X1556049D02*
X1556149D01*
Y49662D01*
X1561149D01*
Y38368D01*
X1556049D01*
Y49462D01*
G37*
G36*
G01X646600Y54400D02*
X646700D01*
Y54600D01*
X651700D01*
Y43700D01*
X646600D01*
Y54400D01*
G37*
G36*
G01X662348D02*
X662448D01*
Y54600D01*
X667448D01*
Y43700D01*
X662348D01*
Y54400D01*
G37*
G36*
G01X678096D02*
X678196D01*
Y54600D01*
X683196D01*
Y43700D01*
X678096D01*
Y54400D01*
G37*
G36*
G01X1516679D02*
X1516779D01*
Y54600D01*
X1521779D01*
Y43700D01*
X1516679D01*
Y54400D01*
G37*
G36*
G01X1532427D02*
X1532527D01*
Y54600D01*
X1537527D01*
Y43700D01*
X1532427D01*
Y54400D01*
G37*
G36*
G01X1548175D02*
X1548275D01*
Y54600D01*
X1553275D01*
Y43700D01*
X1548175D01*
Y54400D01*
G37*
G36*
G01X658668Y74450D02*
X664952D01*
X665860Y73542D01*
Y72258D01*
X664952Y71350D01*
X658668D01*
X657760Y72258D01*
Y73542D01*
X658668Y74450D01*
G37*
G36*
G01X756287D02*
X762571D01*
X763479Y73542D01*
Y72258D01*
X762571Y71350D01*
X756287D01*
X755379Y72258D01*
Y73542D01*
X756287Y74450D01*
G37*
G36*
G01X1528747D02*
X1535031D01*
X1535939Y73542D01*
Y72258D01*
X1535031Y71350D01*
X1528747D01*
X1527839Y72258D01*
Y73542D01*
X1528747Y74450D01*
G37*
G36*
G01X1626366D02*
X1632650D01*
X1633558Y73542D01*
Y72258D01*
X1632650Y71350D01*
X1626366D01*
X1625458Y72258D01*
Y73542D01*
X1626366Y74450D01*
G37*
G36*
G01X653758Y98650D02*
X655042D01*
X655950Y97742D01*
Y91458D01*
X655042Y90550D01*
X653758D01*
X652850Y91458D01*
Y97742D01*
X653758Y98650D01*
G37*
G36*
G01X701028D02*
X702312D01*
X703220Y97742D01*
Y91458D01*
X702312Y90550D01*
X701028D01*
X700120Y91458D01*
Y97742D01*
X701028Y98650D01*
G37*
G36*
G01X1523837D02*
X1525121D01*
X1526029Y97742D01*
Y91458D01*
X1525121Y90550D01*
X1523837D01*
X1522929Y91458D01*
Y97742D01*
X1523837Y98650D01*
G37*
G36*
G01X1571107D02*
X1572391D01*
X1573299Y97742D01*
Y91458D01*
X1572391Y90550D01*
X1571107D01*
X1570199Y91458D01*
Y97742D01*
X1571107Y98650D01*
G37*
G36*
G01X777558Y98680D02*
X778842D01*
X779750Y97772D01*
Y91488D01*
X778842Y90580D01*
X777558D01*
X776650Y91488D01*
Y97772D01*
X777558Y98680D01*
G37*
G36*
G01X1647637D02*
X1648921D01*
X1649829Y97772D01*
Y91488D01*
X1648921Y90580D01*
X1647637D01*
X1646729Y91488D01*
Y97772D01*
X1647637Y98680D01*
G37*
G36*
G01X746838Y94380D02*
X753122D01*
X754030Y93472D01*
Y92188D01*
X753122Y91280D01*
X746838D01*
X745930Y92188D01*
Y93472D01*
X746838Y94380D01*
G37*
G36*
G01X1616917D02*
X1623201D01*
X1624109Y93472D01*
Y92188D01*
X1623201Y91280D01*
X1616917D01*
X1616009Y92188D01*
Y93472D01*
X1616917Y94380D01*
G37*
G36*
G01X671996Y94840D02*
X678280D01*
X679188Y93932D01*
Y92648D01*
X678280Y91740D01*
X671996D01*
X671088Y92648D01*
Y93932D01*
X671996Y94840D01*
G37*
G36*
G01X1542075D02*
X1548359D01*
X1549267Y93932D01*
Y92648D01*
X1548359Y91740D01*
X1542075D01*
X1541167Y92648D01*
Y93932D01*
X1542075Y94840D01*
G37*
G36*
G01X723758Y107150D02*
X730042D01*
X730950Y106242D01*
Y104958D01*
X730042Y104050D01*
X723758D01*
X722850Y104958D01*
Y106242D01*
X723758Y107150D01*
G37*
G36*
G01X1593836D02*
X1600120D01*
X1601028Y106242D01*
Y104958D01*
X1600120Y104050D01*
X1593836D01*
X1592928Y104958D01*
Y106242D01*
X1593836Y107150D01*
G37*
G36*
G01X724668Y116940D02*
X730952D01*
X731860Y116032D01*
Y114748D01*
X730952Y113840D01*
X724668D01*
X723760Y114748D01*
Y116032D01*
X724668Y116940D01*
G37*
G36*
G01X1594746D02*
X1601030D01*
X1601938Y116032D01*
Y114748D01*
X1601030Y113840D01*
X1594746D01*
X1593838Y114748D01*
Y116032D01*
X1594746Y116940D01*
G37*
G36*
G01X764161Y121880D02*
X770445D01*
X771353Y120972D01*
Y119688D01*
X770445Y118780D01*
X764161D01*
X763253Y119688D01*
Y120972D01*
X764161Y121880D01*
G37*
G36*
G01X1634239D02*
X1640523D01*
X1641431Y120972D01*
Y119688D01*
X1640523Y118780D01*
X1634239D01*
X1633331Y119688D01*
Y120972D01*
X1634239Y121880D01*
G37*
G36*
G01X745263Y122002D02*
X751547D01*
X752455Y121094D01*
Y119810D01*
X751547Y118902D01*
X745263D01*
X744355Y119810D01*
Y121094D01*
X745263Y122002D01*
G37*
G36*
G01X1615341D02*
X1621625D01*
X1622533Y121094D01*
Y119810D01*
X1621625Y118902D01*
X1615341D01*
X1614433Y119810D01*
Y121094D01*
X1615341Y122002D01*
G37*
G36*
G01X660972Y122550D02*
X667256D01*
X668164Y121642D01*
Y120358D01*
X667256Y119450D01*
X660972D01*
X660064Y120358D01*
Y121642D01*
X660972Y122550D01*
G37*
G36*
G01X1531050D02*
X1537334D01*
X1538242Y121642D01*
Y120358D01*
X1537334Y119450D01*
X1531050D01*
X1530142Y120358D01*
Y121642D01*
X1531050Y122550D01*
G37*
G36*
G01X689319Y123580D02*
X695603D01*
X696511Y122672D01*
Y121388D01*
X695603Y120480D01*
X689319D01*
X688411Y121388D01*
Y122672D01*
X689319Y123580D01*
G37*
G36*
G01X1559397D02*
X1565681D01*
X1566589Y122672D01*
Y121388D01*
X1565681Y120480D01*
X1559397D01*
X1558489Y121388D01*
Y122672D01*
X1559397Y123580D01*
G37*
G36*
G01X754768Y126280D02*
X761052D01*
X761960Y125372D01*
Y124088D01*
X761052Y123180D01*
X754768D01*
X753860Y124088D01*
Y125372D01*
X754768Y126280D01*
G37*
G36*
G01X1624846D02*
X1631130D01*
X1632038Y125372D01*
Y124088D01*
X1631130Y123180D01*
X1624846D01*
X1623938Y124088D01*
Y125372D01*
X1624846Y126280D01*
G37*
G36*
G01X670421Y127480D02*
X676705D01*
X677613Y126572D01*
Y125288D01*
X676705Y124380D01*
X670421D01*
X669513Y125288D01*
Y126572D01*
X670421Y127480D01*
G37*
G36*
G01X1540499D02*
X1546783D01*
X1547691Y126572D01*
Y125288D01*
X1546783Y124380D01*
X1540499D01*
X1539591Y125288D01*
Y126572D01*
X1540499Y127480D01*
G37*
G36*
G01X679970Y131150D02*
X686254D01*
X687162Y130242D01*
Y128958D01*
X686254Y128050D01*
X679970D01*
X679062Y128958D01*
Y130242D01*
X679970Y131150D01*
G37*
G36*
G01X1550048D02*
X1556332D01*
X1557240Y130242D01*
Y128958D01*
X1556332Y128050D01*
X1550048D01*
X1549140Y128958D01*
Y130242D01*
X1550048Y131150D01*
G37*
G36*
G01X83188Y71770D02*
X82328D01*
G02X82327Y73896I3538J1065D01*
G01X83185D01*
G03X83617Y74144I0J500D01*
G02X84604Y75110I2248J-1310D01*
G03X84862Y75548I-242J438D01*
G01Y76390D01*
G02X86870I1004J-3555D01*
G01Y75548D01*
G03X87128Y75110I500J0D01*
G02X88119Y74136I-1262J-2275D01*
G03X88552Y73886I433J250D01*
G01X89408D01*
G02X89560Y72835I-3542J-1049D01*
G02X89404Y71770I-3694J-3D01*
G01X88544D01*
G03X88112Y71522I0J-500D01*
G02X87126Y70559I-2246J1313D01*
G03X86868Y70121I242J-438D01*
G01Y69279D01*
G02X84864I-1002J3556D01*
G01Y70121D01*
G03X84606Y70559I-500J0D01*
G02X83620Y71522I1260J2276D01*
G03X83188Y71770I-432J-252D01*
G37*
G36*
G01Y103266D02*
X82328D01*
G02X82327Y105392I3538J1065D01*
G01X83185D01*
G03X83617Y105640I0J500D01*
G02X84604Y106606I2248J-1310D01*
G03X84862Y107044I-242J438D01*
G01Y107886D01*
G02X86870I1004J-3555D01*
G01Y107044D01*
G03X87128Y106606I500J0D01*
G02X88119Y105632I-1262J-2275D01*
G03X88552Y105382I433J250D01*
G01X89408D01*
G02X89560Y104331I-3542J-1049D01*
G02X89404Y103266I-3694J-3D01*
G01X88544D01*
G03X88112Y103018I0J-500D01*
G02X87126Y102055I-2246J1313D01*
G03X86868Y101617I242J-438D01*
G01Y100775D01*
G02X84864I-1002J3556D01*
G01Y101617D01*
G03X84606Y102055I-500J0D01*
G02X83620Y103018I1260J2276D01*
G03X83188Y103266I-432J-252D01*
G37*
G54D41*
X1336729Y49150D03*
X466650D03*
X1376099Y44032D03*
X506020D03*
X1336729Y32615D03*
X466650D03*
X1376099Y27497D03*
X506020D03*
G54D43*
X1647618Y132244D03*
X1572775D03*
X777539D03*
X702697D03*
G54D49*
X40827Y147638D03*
Y29528D03*
G54D44*
X1600374Y132244D03*
X1525531D03*
X1412164Y56653D03*
X1262872Y56654D03*
X730295Y132244D03*
X655453D03*
X542085Y56654D03*
X392793Y56653D03*
G54D45*
X1378938Y176650D03*
X508859D03*
G54D46*
X1333938D03*
X463859D03*
G54D47*
X1221732Y37400D03*
G54D42*
X1291985Y40500D03*
X1273087D03*
X571198D03*
X552300D03*
X1441277Y40499D03*
X1422379D03*
X421906D03*
X403008D03*
G54D50*
X17717Y18504D03*
X1670512D03*
G54D48*
X351654Y37401D03*
G54D18*
X64500Y165200D03*
X99100Y127470D03*
X89400Y165300D03*
X111958Y73600D03*
X121958Y70900D03*
X116958Y68600D03*
X106958Y68500D03*
X122758Y82442D03*
X117158Y82542D03*
X112158Y82342D03*
X106958Y82142D03*
X102590Y115680D03*
X115400Y120270D03*
X107390Y125110D03*
X119800Y124390D03*
X108900Y137300D03*
X114300Y134900D03*
X119700Y132400D03*
X111500Y129900D03*
X105800Y165400D03*
X125558Y79642D03*
X128600Y114510D03*
X132500Y110100D03*
X125000Y126400D03*
X350700Y121642D03*
X345900Y125100D03*
X347350Y143750D03*
X346906Y137693D03*
X357800Y114657D03*
X357600Y108561D03*
X356861Y102961D03*
X367200Y124000D03*
X405531Y21960D03*
X400531D03*
X400100Y13900D03*
X412800Y16200D03*
X410906Y46100D03*
X414055Y46200D03*
X412480Y80900D03*
X403032Y89532D03*
X415630Y80700D03*
X412300Y85600D03*
X421929Y78400D03*
X409331Y88600D03*
X406181Y82300D03*
X399882Y79318D03*
X447880Y36200D03*
X453480D03*
X453900Y92300D03*
X466200Y87558D03*
X453300Y86800D03*
X451100Y81400D03*
X452100Y97000D03*
X466100Y83258D03*
X452000Y102200D03*
X466300Y100900D03*
X488800Y73700D03*
Y93800D03*
X511600Y108000D03*
X523300Y15580D03*
Y20580D03*
X525700Y99300D03*
X519400Y96400D03*
X520439Y91000D03*
X516500Y87442D03*
X526612Y142000D03*
X559425Y13575D03*
X560198Y46100D03*
X558623Y79200D03*
X552324Y78500D03*
X549174Y89400D03*
X582416Y16466D03*
X573721Y22500D03*
X568721D03*
X563347Y46100D03*
X571221Y79700D03*
X568072Y81500D03*
X564922Y81900D03*
X561772Y80800D03*
X563800Y87700D03*
X604400Y96000D03*
X604200Y107400D03*
X614900Y90157D03*
X615600Y95139D03*
X615500Y100157D03*
X622658Y112158D03*
X622200Y120258D03*
X615500Y105157D03*
X626173Y148400D03*
X617949Y147000D03*
X659310Y72900D03*
X664310D03*
X654400Y92100D03*
Y97100D03*
X672638Y93290D03*
X666614Y121000D03*
X661614D03*
X671063Y125930D03*
X676063D03*
X677638Y93290D03*
X689961Y122030D03*
X694961D03*
X680612Y129600D03*
X685612D03*
X701100Y16900D03*
X701670Y97100D03*
Y92100D03*
X724400Y105600D03*
X729400D03*
X730310Y115390D03*
X725310D03*
X761929Y72900D03*
X756929D03*
X752480Y92830D03*
X747480D03*
X745905Y120452D03*
X750905D03*
X764803Y120330D03*
X760410Y124730D03*
X755410D03*
X778200Y92130D03*
Y97130D03*
X769803Y120330D03*
X1226900Y119561D03*
Y114043D03*
X1227000Y108361D03*
X1227100Y102861D03*
X1219600Y129400D03*
X1219400Y123900D03*
X1211200Y144900D03*
X1217405Y143895D03*
X1238900Y123300D03*
X1238100Y127900D03*
X1270610Y21960D03*
X1268700Y14000D03*
X1273111Y89100D03*
X1269961Y78400D03*
X1275610Y21960D03*
X1289775Y11975D03*
X1284134Y46100D03*
X1280985Y46200D03*
X1292008Y80192D03*
X1288859Y78400D03*
X1279410Y87200D03*
X1285709Y84300D03*
X1276260Y79000D03*
X1282559Y85700D03*
X1317959Y36200D03*
X1323559D03*
X1333400Y82900D03*
X1323000Y99239D03*
X1321400Y92800D03*
X1329500Y81400D03*
X1321500Y82600D03*
X1322500Y87800D03*
X1335600Y96500D03*
X1358200Y69000D03*
X1358600Y73700D03*
X1345100Y105500D03*
X1387400Y87242D03*
X1389900Y97600D03*
X1371600Y96000D03*
X1393379Y20580D03*
Y15580D03*
X1395200Y99500D03*
X1391000Y92400D03*
X1429525Y13775D03*
X1433426Y46100D03*
X1430277D03*
X1422403Y78400D03*
X1434200Y88100D03*
X1435001Y81700D03*
X1431851Y80200D03*
X1428702Y79002D03*
X1429400Y88500D03*
X1443800Y22500D03*
X1438800D03*
X1454600Y17600D03*
X1441300Y79100D03*
X1438151Y81100D03*
X1472400Y102700D03*
X1474200Y106600D03*
X1484700Y93057D03*
X1485000Y98057D03*
X1484900Y103257D03*
X1492300Y117558D03*
X1484800Y109357D03*
X1492042Y126358D03*
X1495800Y147800D03*
X1487600Y147000D03*
X1524478Y97100D03*
Y92100D03*
X1534388Y72900D03*
X1529388D03*
X1542716Y93290D03*
X1547716D03*
X1531692Y121000D03*
X1536692D03*
X1546141Y125930D03*
X1550690Y129600D03*
X1541141Y125930D03*
X1570800Y18900D03*
X1571748Y92100D03*
Y97100D03*
X1565039Y122030D03*
X1560039D03*
X1555690Y129600D03*
X1594478Y105600D03*
X1595388Y115390D03*
X1617558Y92830D03*
X1599478Y105600D03*
X1600388Y115390D03*
X1615983Y120452D03*
X1627007Y72900D03*
X1632007D03*
X1622558Y92830D03*
X1620983Y120452D03*
X1639881Y120330D03*
X1634881D03*
X1625488Y124730D03*
X1630488D03*
X1648278Y97130D03*
Y92130D03*
G54D17*
X51900Y162300D03*
X53200Y169500D03*
X76900Y20200D03*
X65600Y160400D03*
X57200Y165300D03*
X73200Y162100D03*
X62200Y169900D03*
X70400Y170000D03*
X90200Y22400D03*
X94900Y144500D03*
X83800Y154500D03*
X99000Y148900D03*
X78800Y158000D03*
X93900Y162900D03*
X90200Y169500D03*
X81600Y162600D03*
X92600Y154800D03*
X100700Y163400D03*
X89000Y150200D03*
X88000Y158900D03*
X83500Y169700D03*
X78200Y169900D03*
X96900Y169500D03*
X98000Y157100D03*
X102500Y29400D03*
X107200Y19300D03*
X121200Y33900D03*
X102000Y141900D03*
X114000Y145200D03*
X119900Y143200D03*
X108600Y143100D03*
X111800Y151800D03*
X104900Y157400D03*
X120500Y157200D03*
X111900Y164800D03*
X118100Y162100D03*
X104500Y150300D03*
X110900Y159200D03*
X118400Y152000D03*
X106500Y170300D03*
X115300Y170200D03*
X123900Y41000D03*
X138700Y63500D03*
X144100Y72900D03*
X139800Y90200D03*
X131400Y91300D03*
X129200Y101300D03*
Y142400D03*
X126600Y149500D03*
X165600Y19400D03*
X168100Y48400D03*
X151500Y35800D03*
X159800Y65100D03*
X161800Y86800D03*
X158200Y102400D03*
X184100Y36600D03*
X174300Y73300D03*
X181400Y84700D03*
X194400Y20200D03*
X197800Y30900D03*
Y48000D03*
X214700Y35800D03*
X195600Y64100D03*
X206700Y72700D03*
X225800Y19600D03*
X229200Y30900D03*
X216400Y100500D03*
X254400Y19200D03*
X257800Y51200D03*
X244900Y36600D03*
X254400Y74300D03*
X251600Y100100D03*
X252200Y159400D03*
X252800Y179900D03*
X268300Y36200D03*
X283600Y69500D03*
X273300Y94900D03*
X281800Y100900D03*
X267700Y145200D03*
X280000Y159800D03*
X281000Y180700D03*
X307800Y101100D03*
X300300Y140000D03*
X350000Y161800D03*
X350200Y181100D03*
X466654Y29922D03*
Y18898D03*
Y13386D03*
Y51969D03*
Y46457D03*
Y35433D03*
X474528Y8268D03*
X490276D03*
X474528Y30315D03*
X482402Y29922D03*
X490276Y30315D03*
X474528Y24803D03*
X490276D03*
X482402Y18898D03*
X474528Y13780D03*
X482402Y13386D03*
X490276Y13780D03*
X474528Y52362D03*
X482402Y51969D03*
X490276Y52362D03*
X474528Y46851D03*
X482402Y46457D03*
X490276Y46851D03*
X474528Y41339D03*
X482402Y40945D03*
X490276Y41339D03*
X482402Y35433D03*
X490276Y35827D03*
X506024Y8268D03*
X498150Y29922D03*
X506024Y30315D03*
Y24803D03*
X498150Y18898D03*
Y13386D03*
X506024Y13780D03*
X498150Y51969D03*
Y46457D03*
X506024Y46851D03*
Y41339D03*
X498150Y35433D03*
X649173Y29922D03*
Y18898D03*
Y13386D03*
Y51969D03*
Y46457D03*
Y35433D03*
X657047Y8268D03*
X672795D03*
X657047Y30315D03*
X664921Y29922D03*
X672795Y30315D03*
X657047Y24803D03*
X672795D03*
X664921Y18898D03*
X657047Y13780D03*
X664921Y13386D03*
X672795Y13780D03*
X664921Y51969D03*
X657047Y46851D03*
X664921Y46457D03*
X672795Y46851D03*
X657047Y41339D03*
X672795D03*
X664921Y35433D03*
X688543Y8268D03*
X680669Y29922D03*
X688543Y30315D03*
Y24803D03*
X680669Y18898D03*
Y13386D03*
X688543Y13780D03*
X680669Y51969D03*
Y46457D03*
X688543Y46851D03*
Y41339D03*
X680669Y35433D03*
X813700Y43900D03*
X809700Y86500D03*
X839700D03*
X838300Y128100D03*
X855400Y152400D03*
X857000Y189800D03*
X869700Y86500D03*
X868300Y128100D03*
X899700Y86500D03*
X898300Y128100D03*
X885400Y152400D03*
X887000Y189800D03*
X929700Y86500D03*
X928300Y128100D03*
X915400Y152400D03*
X917000Y189800D03*
X945400Y152400D03*
X947000Y189800D03*
X959000Y18000D03*
X959700Y86500D03*
X958300Y128100D03*
X975400Y152400D03*
X989700Y86500D03*
X988300Y128100D03*
X977000Y189800D03*
X1018300Y128100D03*
X1005400Y152400D03*
X1007000Y189800D03*
X1043000Y45500D03*
X1031900Y84100D03*
X1035400Y152400D03*
X1037000Y189800D03*
X1063700Y15300D03*
X1061900Y84100D03*
X1048300Y128100D03*
X1065400Y152400D03*
X1067000Y189800D03*
X1073000Y45500D03*
X1078300Y128100D03*
X1091900Y84100D03*
X1108300Y128100D03*
X1095400Y152400D03*
X1097000Y189800D03*
X1120900Y64500D03*
X1121900Y84100D03*
X1125400Y152400D03*
X1127000Y189800D03*
X1147100Y64500D03*
X1151900Y84100D03*
X1155400Y152400D03*
X1157000Y189800D03*
X1344607Y8268D03*
X1336733Y29922D03*
X1344607Y30315D03*
Y24803D03*
X1336733Y18898D03*
Y13386D03*
X1344607Y13780D03*
X1336733Y51969D03*
X1344607Y52362D03*
X1336733Y46457D03*
X1344607Y46851D03*
Y41339D03*
X1336733Y35433D03*
X1360355Y8268D03*
X1352481Y29922D03*
X1360355Y30315D03*
Y24803D03*
X1352481Y18898D03*
Y13386D03*
X1360355Y13780D03*
X1352481Y51969D03*
X1360355Y52362D03*
X1352481Y46457D03*
X1360355Y46851D03*
X1352481Y40945D03*
X1360355Y41339D03*
X1352481Y35433D03*
X1360355Y35827D03*
X1376103Y8268D03*
X1368229Y29922D03*
X1376103Y30315D03*
Y24803D03*
X1368229Y18898D03*
Y13386D03*
X1376103Y13780D03*
X1368229Y51969D03*
Y46457D03*
X1376103Y46851D03*
Y41339D03*
X1368229Y35433D03*
X1527126Y8268D03*
X1519252Y29922D03*
X1527126Y30315D03*
Y24803D03*
X1519252Y18898D03*
Y13386D03*
X1527126Y13780D03*
X1519252Y51969D03*
Y46457D03*
X1527126Y46851D03*
Y41339D03*
X1519252Y35433D03*
X1542874Y8268D03*
X1535000Y29922D03*
X1542874Y30315D03*
X1550748Y29922D03*
X1542874Y24803D03*
X1535000Y18898D03*
X1550748D03*
X1535000Y13386D03*
X1542874Y13780D03*
X1550748Y13386D03*
X1535000Y51969D03*
X1550748D03*
X1535000Y46457D03*
X1542874Y46851D03*
X1550748Y46457D03*
X1542874Y41339D03*
X1535000Y35433D03*
X1550748D03*
X1558622Y8268D03*
Y30315D03*
Y24803D03*
Y13780D03*
Y46851D03*
Y41339D03*
G54D28*
X367402Y11810D03*
Y19684D03*
Y27558D03*
X359528Y11810D03*
Y19684D03*
Y27558D03*
X367402Y43306D03*
Y51180D03*
X359528Y43306D03*
Y51180D03*
X367402Y59054D03*
X359528D03*
X1229606Y11810D03*
Y19684D03*
Y27558D03*
Y43306D03*
Y51180D03*
Y59054D03*
X1237480Y11810D03*
Y19684D03*
Y27558D03*
Y43306D03*
Y51180D03*
Y59054D03*
G54D15*
X44528Y41339D03*
Y53150D03*
Y64961D03*
Y76772D03*
Y88583D03*
Y100394D03*
Y112205D03*
Y124016D03*
Y135827D03*
G54D19*
X85866Y72835D03*
Y104331D03*
G54D14*
X40827Y29528D03*
Y147638D03*
G54D33*
X439744Y60217D03*
X589036D03*
X1309823D03*
X1459114D03*
G54D34*
X468859Y115666D03*
Y141650D03*
X488859Y115666D03*
X478859D03*
X483859Y125666D03*
X473859D03*
X478859Y141650D03*
X488859D03*
X473859Y151650D03*
X483859D03*
X498859Y115666D03*
X503859Y125666D03*
X493859D03*
X498859Y141650D03*
X493859Y151650D03*
X503859D03*
X1338938Y115666D03*
X1343938Y125666D03*
X1338938Y141650D03*
X1343938Y151650D03*
X1358938Y115666D03*
X1348938D03*
X1363938Y125666D03*
X1353938D03*
X1348938Y141650D03*
X1358938D03*
X1353938Y151650D03*
X1363938D03*
X1368938Y115666D03*
X1373938Y125666D03*
X1368938Y141650D03*
X1373938Y151650D03*
G54D11*
X9088Y80158D03*
Y91958D03*
X19088Y80158D03*
Y91958D03*
X109288Y92458D03*
X119288D03*
X109288Y103958D03*
X119288D03*
G54D30*
X392795Y56653D03*
X542087Y56654D03*
X655453Y132244D03*
X702697D03*
X730295D03*
X777539D03*
X1262874Y56654D03*
X1412166Y56653D03*
X1525531Y132244D03*
X1572775D03*
X1600374D03*
X1647618D03*
G54D20*
X81929Y76772D03*
Y68898D03*
X89803Y76772D03*
Y68898D03*
X81929Y100394D03*
Y92520D03*
Y84646D03*
X89803Y100394D03*
Y92520D03*
Y84646D03*
X81929Y108268D03*
G54D24*
X102400Y59600D03*
G54D37*
X477630Y88900D03*
X575600Y7600D03*
X571500Y7500D03*
X567500Y7300D03*
X563100Y7200D03*
X1433700Y8000D03*
X1442400Y8200D03*
X1438000Y8100D03*
X1446300Y8300D03*
G54D29*
X392776Y32264D03*
X383642Y50375D03*
Y70060D03*
Y88564D03*
X411673Y32264D03*
X430571D03*
X439744Y50375D03*
Y70060D03*
Y88564D03*
X532934Y50375D03*
Y70060D03*
Y88564D03*
X542068Y32264D03*
X560965D03*
X579863D03*
X589036Y50375D03*
Y70060D03*
Y88564D03*
X1262855Y32264D03*
X1253721Y50375D03*
Y70060D03*
Y88564D03*
X1281752Y32264D03*
X1300650D03*
X1309823Y50375D03*
Y70060D03*
Y88564D03*
X1412146Y32264D03*
X1403012Y50375D03*
Y70060D03*
Y88564D03*
X1431043Y32264D03*
X1449941D03*
X1459114Y50375D03*
Y70060D03*
Y88564D03*
G54D22*
X123100Y49600D03*
X143300Y27300D03*
X143800Y53600D03*
X144500Y40000D03*
X133100Y71300D03*
X144200Y96300D03*
X143000Y105700D03*
X141900Y154700D03*
X134800Y164000D03*
X144700Y149200D03*
X137100Y158600D03*
X137000Y170400D03*
X127400D03*
X150300Y20200D03*
X166500Y34700D03*
X153100Y49600D03*
X148800Y85000D03*
X163500Y144900D03*
X150300Y144600D03*
X156000Y138200D03*
X156500Y144800D03*
X169900Y146800D03*
X164400Y138200D03*
X169400Y153600D03*
X155600Y157900D03*
X162100Y164300D03*
X168000Y161200D03*
X149300Y164100D03*
X163200Y151600D03*
X162000Y159400D03*
X148000Y158800D03*
X152600Y152000D03*
X155900Y170000D03*
X163800Y170100D03*
X148600D03*
X180300Y20200D03*
X183100Y49600D03*
X191700Y75400D03*
X175000Y62300D03*
X174200Y96300D03*
X190400Y136600D03*
X191200Y142400D03*
X178100Y144600D03*
X184000Y138800D03*
X173600Y138700D03*
X185800Y145400D03*
X190000Y149800D03*
X179300Y156400D03*
X187100Y155800D03*
X192100Y163500D03*
X176300Y164400D03*
X175500Y151300D03*
X173700Y158700D03*
X190400Y169800D03*
X182600Y152000D03*
X171300Y170000D03*
X177800Y170400D03*
X210300Y20200D03*
X213100Y49600D03*
X209400Y60900D03*
X204200Y96300D03*
X196200Y102300D03*
X211300Y138600D03*
X204200Y139200D03*
X195900Y146300D03*
X213300Y146800D03*
X197300Y139100D03*
X205100Y147700D03*
X201500Y154400D03*
X213500Y155400D03*
X197100Y160800D03*
X194600Y154800D03*
X227100Y43000D03*
X234200Y96300D03*
X225600Y104500D03*
X234500Y138700D03*
X230600Y146400D03*
X218100Y140500D03*
X224400Y138200D03*
X236800Y165000D03*
X238800Y157500D03*
X231600Y155100D03*
X221800Y149400D03*
X236500Y185900D03*
X235400Y172900D03*
X240300Y20200D03*
X243100Y49600D03*
X248600Y142900D03*
X242600Y140100D03*
X254400Y138200D03*
X239600Y148700D03*
X245100Y165200D03*
X255400Y148400D03*
X245600Y157000D03*
X248400Y149800D03*
X239800Y178700D03*
X243300Y185600D03*
X242300Y171800D03*
X252600Y192000D03*
X242400Y193300D03*
X270300Y20200D03*
X273100Y49600D03*
X264200Y96300D03*
X262900Y104900D03*
X284400Y138200D03*
X265300Y170000D03*
X282600Y192000D03*
X294200Y96300D03*
X287600Y150000D03*
X292800Y169800D03*
X324200Y96300D03*
X314600Y104100D03*
X310200Y135900D03*
X338300Y162900D03*
Y183800D03*
X359200Y164900D03*
X359100Y184400D03*
X466654Y7874D03*
Y24410D03*
Y40945D03*
X482402Y7874D03*
Y24410D03*
X474528Y19292D03*
X490276D03*
X474528Y35827D03*
X498150Y7874D03*
Y24410D03*
X506024Y19292D03*
Y52362D03*
X498150Y40945D03*
X506024Y35827D03*
X649173Y7874D03*
Y24410D03*
Y40945D03*
X664921Y7874D03*
Y24410D03*
X657047Y19292D03*
X672795D03*
X657047Y52362D03*
X672795D03*
X664921Y40945D03*
X657047Y35827D03*
X672795D03*
X680669Y7874D03*
Y24410D03*
X688543Y19292D03*
Y52362D03*
X680669Y40945D03*
X688543Y35827D03*
X806800Y26700D03*
X810700Y65200D03*
X836800Y26700D03*
X825200Y111700D03*
X840700Y65200D03*
X855200Y111700D03*
X855400Y173000D03*
X866800Y26700D03*
X870700Y65200D03*
X896800Y26700D03*
X900700Y65200D03*
X885200Y111700D03*
X885400Y173000D03*
X926800Y26700D03*
X915200Y111700D03*
X915400Y173000D03*
X930700Y65200D03*
X945200Y111700D03*
X945400Y173000D03*
X956800Y26700D03*
X960700Y65200D03*
X975200Y111700D03*
X975400Y173000D03*
X986800Y26700D03*
X990700Y65200D03*
X1018800Y26300D03*
X1005200Y111700D03*
X1005400Y173000D03*
X1022700Y64800D03*
X1037200Y111300D03*
X1035400Y173000D03*
X1048800Y26300D03*
X1052700Y64800D03*
X1067200Y111300D03*
X1067400Y172600D03*
X1078800Y26300D03*
X1082700Y64800D03*
X1097200Y111300D03*
X1097400Y172600D03*
X1136600Y19700D03*
X1135400Y41000D03*
X1127200Y111300D03*
X1127400Y172600D03*
X1157400D03*
X1336733Y7874D03*
Y24410D03*
X1344607Y19292D03*
X1336733Y40945D03*
X1344607Y35827D03*
X1352481Y7874D03*
Y24410D03*
X1360355Y19292D03*
X1368229Y7874D03*
Y24410D03*
X1376103Y19292D03*
Y52362D03*
X1368229Y40945D03*
X1376103Y35827D03*
X1519252Y7874D03*
Y24410D03*
X1527126Y19292D03*
Y52362D03*
X1519252Y40945D03*
X1527126Y35827D03*
X1535000Y7874D03*
X1550748D03*
X1535000Y24410D03*
X1550748D03*
X1542874Y19292D03*
Y52362D03*
X1535000Y40945D03*
X1550748D03*
X1542874Y35827D03*
X1558622Y19292D03*
Y52362D03*
Y35827D03*
G54D26*
X343780Y11810D03*
Y19684D03*
Y27558D03*
X335906Y11810D03*
Y19684D03*
Y27558D03*
X343780Y43306D03*
Y51180D03*
X335906Y43306D03*
Y51180D03*
X343780Y59054D03*
X335906D03*
X1205984Y11810D03*
Y19684D03*
Y27558D03*
Y43306D03*
Y51180D03*
Y59054D03*
X1213858Y11810D03*
Y19684D03*
Y27558D03*
Y43306D03*
Y51180D03*
Y59054D03*
G54D35*
X452875Y131650D03*
X455867Y153658D03*
X452875Y194642D03*
X516851Y140666D03*
X519843Y115666D03*
Y194642D03*
X1322954Y131650D03*
Y194642D03*
X1325946Y153658D03*
X1389922Y115666D03*
X1386930Y140666D03*
X1389922Y194642D03*
G54D31*
X383642Y40532D03*
Y79902D03*
X396122Y99587D03*
X383642Y119272D03*
Y158642D03*
X417382Y99587D03*
X405964Y178327D03*
X439744Y99587D03*
Y138957D03*
Y178327D03*
X532934Y40532D03*
Y79902D03*
Y119272D03*
Y158642D03*
X545414Y99587D03*
X555256Y178327D03*
X566674Y99587D03*
X589036D03*
Y138957D03*
Y178327D03*
X1253721Y40532D03*
Y79902D03*
Y119272D03*
Y158642D03*
X1266201Y99587D03*
X1276043Y178327D03*
X1287461Y99587D03*
X1309823D03*
Y138957D03*
Y178327D03*
X1403012Y40532D03*
Y79902D03*
Y119272D03*
Y158642D03*
X1415492Y99587D03*
X1436752D03*
X1425334Y178327D03*
X1459114Y99587D03*
Y138957D03*
Y178327D03*
G54D38*
X639283Y108622D03*
Y167677D03*
X793693Y108622D03*
Y167677D03*
X1509362Y108622D03*
Y167677D03*
X1663772Y108622D03*
Y167677D03*
G54D21*
X89803Y108268D03*
G54D25*
X306772Y19685D03*
Y41850D03*
Y67913D03*
X612047Y19685D03*
Y41850D03*
Y67913D03*
X1176851Y19685D03*
Y41850D03*
Y67913D03*
X1482126Y19685D03*
Y41850D03*
Y67913D03*
G54D16*
X56339Y41339D03*
Y53150D03*
Y64961D03*
Y76772D03*
Y88583D03*
Y100394D03*
Y112205D03*
Y124016D03*
Y135827D03*
G54D39*
X641212Y132244D03*
X791764D03*
X1511291D03*
X1661843D03*
G54D10*
X8221Y28000D03*
Y9008D03*
X4287Y18504D03*
X17717Y5074D03*
X27213Y28000D03*
X31147Y18504D03*
X27213Y9008D03*
X17717Y31934D03*
X1661016Y28000D03*
Y9008D03*
X1657082Y18504D03*
X1670512Y5074D03*
X1680008Y28000D03*
X1683942Y18504D03*
X1680008Y9008D03*
X1670512Y31934D03*
G54D27*
X351654Y37400D03*
X1221732D03*
G54D12*
X17717Y18504D03*
X1670512D03*
G54D36*
X463859Y176650D03*
X508859D03*
X1333938D03*
X1378938D03*
G54D13*
X17716Y114173D03*
X314213Y163386D03*
X783661Y18504D03*
X826024Y163386D03*
X1101615Y18504D03*
X1184292Y163386D03*
G54D32*
X430591Y56653D03*
X579883Y56654D03*
X1300670D03*
X1449962Y56653D03*
G54D23*
X120500Y59400D03*
X114400Y59700D03*
X107500Y59500D03*
X141400Y164800D03*
X129000D03*
X169200Y165200D03*
X155500Y164800D03*
X183300Y164700D03*
X346800Y113500D03*
X345400Y107600D03*
X346200Y102500D03*
X362500Y97100D03*
X357600Y97000D03*
X397800Y23600D03*
Y19500D03*
X398307Y35000D03*
Y46100D03*
X396732Y78932D03*
X417900Y6700D03*
X414900Y6500D03*
X410200Y6700D03*
X404400Y6800D03*
X408200Y23500D03*
Y19900D03*
X417205Y35000D03*
X407600D03*
X407756Y46100D03*
X417205D03*
X426500Y35000D03*
X426654Y46100D03*
X426200Y78100D03*
X446000Y38400D03*
Y33900D03*
X455400Y34000D03*
Y38600D03*
X465600Y55900D03*
X463435Y79865D03*
X474500Y3900D03*
X490200Y4000D03*
X488000Y89800D03*
X507200Y4200D03*
X505700Y90200D03*
X520900Y22500D03*
X525600Y22600D03*
Y13900D03*
X520800Y13800D03*
X556900Y35000D03*
X547599D03*
X557048Y46100D03*
X547599D03*
X546024Y79200D03*
X567100Y20500D03*
X575900Y20800D03*
X575800Y24300D03*
X567000Y24400D03*
X575946Y46100D03*
X566497D03*
X575800Y35000D03*
X566497D03*
X574371Y78400D03*
X626100Y99900D03*
X625600Y95400D03*
X625700Y90100D03*
X626600Y106100D03*
X648300Y55600D03*
X651500Y94700D03*
X651100Y91100D03*
X655200Y4100D03*
X661600Y75900D03*
X667200Y75700D03*
X665100Y55900D03*
X670414Y96486D03*
X658400Y102500D03*
X659390Y117490D03*
X668839Y117661D03*
X667500Y126200D03*
X688800Y4100D03*
X680300Y75600D03*
X681600Y55500D03*
X698400Y90300D03*
X689723Y89400D03*
X689311Y96311D03*
X679862Y96538D03*
X678288Y122700D03*
X697185Y117385D03*
X687736Y118700D03*
X685600Y133200D03*
X680900D03*
X701732Y101968D03*
X740300Y87300D03*
X735807Y96593D03*
X745256Y96044D03*
X743681Y117400D03*
X731950Y111850D03*
X723500Y118900D03*
X722400Y102300D03*
X730900Y108900D03*
X753100Y75100D03*
X765600Y74800D03*
X764153Y96153D03*
X754704Y96196D03*
X762578Y117300D03*
X753130D03*
X754300Y121400D03*
X764000Y124700D03*
X774600Y90300D03*
X776032Y101968D03*
X772027Y117300D03*
X1223200Y99000D03*
X1218000Y99100D03*
X1216500Y119500D03*
X1216700Y114400D03*
X1216500Y108300D03*
X1216400Y102600D03*
X1229800Y96400D03*
X1273000Y6100D03*
X1267700Y22900D03*
Y19700D03*
X1268386Y35000D03*
Y46100D03*
X1266811Y78300D03*
X1276700Y5900D03*
X1280900D03*
X1285800D03*
X1278700Y19800D03*
Y23000D03*
X1296600Y35000D03*
X1277700D03*
X1287284D03*
X1296733Y46100D03*
X1287284D03*
X1277835D03*
X1295158Y79158D03*
X1315879Y38200D03*
X1315979Y33900D03*
X1325279Y38600D03*
Y33800D03*
X1335300Y55600D03*
X1340400Y90800D03*
X1360600Y4000D03*
X1344700Y4100D03*
X1359000Y91000D03*
X1376300Y4000D03*
X1371600Y86463D03*
X1395679Y22600D03*
X1390979Y22500D03*
X1390879Y13800D03*
X1395679Y13900D03*
X1417678Y46100D03*
X1427127D03*
X1417678Y35000D03*
X1427000D03*
X1416103Y78400D03*
X1436500Y23900D03*
Y20700D03*
X1445900Y20800D03*
X1445700Y24400D03*
X1446025Y46100D03*
X1436576D03*
X1445900Y35000D03*
X1436576D03*
X1444450Y78300D03*
X1494200Y97800D03*
X1495000Y92800D03*
X1494700Y111200D03*
X1494500Y102700D03*
X1527200Y3800D03*
X1518200Y55600D03*
X1521579Y94700D03*
X1521179Y91100D03*
X1550500Y75500D03*
X1537279Y75700D03*
X1531679Y75900D03*
X1535300Y55800D03*
X1549940Y96538D03*
X1540492Y96486D03*
X1528478Y102500D03*
X1548366Y122700D03*
X1538917Y117661D03*
X1529468Y117490D03*
X1550979Y133200D03*
X1537579Y126200D03*
X1559000Y4200D03*
X1551800Y55700D03*
X1559802Y89400D03*
X1559389Y96311D03*
X1568479Y90300D03*
X1571810Y101968D03*
X1557814Y118700D03*
X1567263Y117385D03*
X1555679Y133200D03*
X1592900Y101700D03*
X1593300Y119000D03*
X1610379Y87300D03*
X1605885Y96593D03*
X1615334Y96044D03*
X1613759Y117400D03*
X1602028Y111850D03*
X1600900Y108700D03*
X1635679Y74800D03*
X1623179Y75100D03*
X1624782Y96196D03*
X1634231Y96153D03*
X1623208Y117300D03*
X1642105D03*
X1632656D03*
X1624300Y121500D03*
X1634179Y124300D03*
X1644679Y90300D03*
X1646110Y101968D03*
X1676100Y78900D03*
%LPC*%
G75*
G54D40*
G01X457212Y-338900D02*
Y-343900D01*
G01X455755Y-338900D02*
X458669D01*
G01X463579Y-343900D02*
X461045D01*
Y-338900D01*
X463579D01*
G01X462565Y-341317D02*
X461045D01*
G01X466145Y-338900D02*
Y-343900D01*
X468679D01*
G01X472512Y-344067D02*
X472385Y-343983D01*
Y-343817D01*
X472512Y-343733D01*
X472639Y-343817D01*
Y-343983D01*
X472512Y-344067D01*
G01Y-341817D02*
X472385Y-341733D01*
Y-341567D01*
X472512Y-341483D01*
X472639Y-341567D01*
Y-341733D01*
X472512Y-341817D01*
G01X477295Y-345567D02*
X476662Y-344733D01*
X476345Y-343900D01*
Y-340567D01*
X476662Y-339733D01*
X477295Y-338900D01*
G01X482712D02*
X482205Y-339067D01*
X481825Y-339483D01*
X481572Y-339983D01*
X481382Y-340650D01*
X481319Y-341400D01*
X481382Y-342150D01*
X481572Y-342817D01*
X481825Y-343317D01*
X482205Y-343733D01*
X482712Y-343900D01*
X483219Y-343733D01*
X483599Y-343317D01*
X483852Y-342817D01*
X484042Y-342150D01*
X484105Y-341400D01*
X484042Y-340650D01*
X483852Y-339983D01*
X483599Y-339483D01*
X483219Y-339067D01*
X482712Y-338900D01*
G01X486419Y-342900D02*
X486799Y-343483D01*
X487305Y-343817D01*
X487875Y-343900D01*
X488382Y-343817D01*
X488889Y-343400D01*
X489205Y-342900D01*
X489269Y-342400D01*
X489142Y-341817D01*
X488699Y-341400D01*
X488255Y-341233D01*
X487685D01*
G01X488255D02*
X488635Y-340983D01*
X488952Y-340567D01*
X489079Y-340067D01*
X488952Y-339567D01*
X488635Y-339150D01*
X488065Y-338900D01*
X487495Y-338983D01*
X486925Y-339317D01*
G01X493229Y-345567D02*
X493862Y-344733D01*
X494179Y-343900D01*
Y-340567D01*
X493862Y-339733D01*
X493229Y-338900D01*
G01X496619Y-342900D02*
X496999Y-343483D01*
X497505Y-343817D01*
X498075Y-343900D01*
X498582Y-343817D01*
X499089Y-343400D01*
X499405Y-342900D01*
X499469Y-342400D01*
X499342Y-341817D01*
X498899Y-341400D01*
X498455Y-341233D01*
X497885D01*
G01X498455D02*
X498835Y-340983D01*
X499152Y-340567D01*
X499279Y-340067D01*
X499152Y-339567D01*
X498835Y-339150D01*
X498265Y-338900D01*
X497695Y-338983D01*
X497125Y-339317D01*
G01X501909Y-339733D02*
X502289Y-339233D01*
X502732Y-338983D01*
X503239Y-338900D01*
X503872Y-339067D01*
X504315Y-339483D01*
X504442Y-339983D01*
X504379Y-340483D01*
X504125Y-340900D01*
X502859Y-341733D01*
X502289Y-342317D01*
X501909Y-343150D01*
X501782Y-343900D01*
X504442D01*
G01X508085D02*
X508212Y-342817D01*
X508402Y-341900D01*
X508655Y-341067D01*
X508972Y-340150D01*
X509479Y-338900D01*
X506945D01*
G01X512489Y-342233D02*
X514135D01*
G01X517209Y-339733D02*
X517589Y-339233D01*
X518032Y-338983D01*
X518539Y-338900D01*
X519172Y-339067D01*
X519615Y-339483D01*
X519742Y-339983D01*
X519679Y-340483D01*
X519425Y-340900D01*
X518159Y-341733D01*
X517589Y-342317D01*
X517209Y-343150D01*
X517082Y-343900D01*
X519742D01*
G01X522119Y-342900D02*
X522499Y-343483D01*
X523005Y-343817D01*
X523575Y-343900D01*
X524082Y-343817D01*
X524589Y-343400D01*
X524905Y-342900D01*
X524969Y-342400D01*
X524842Y-341817D01*
X524399Y-341400D01*
X523955Y-341233D01*
X523385D01*
G01X523955D02*
X524335Y-340983D01*
X524652Y-340567D01*
X524779Y-340067D01*
X524652Y-339567D01*
X524335Y-339150D01*
X523765Y-338900D01*
X523195Y-338983D01*
X522625Y-339317D01*
G01X529372Y-343900D02*
Y-338900D01*
X527029Y-342483D01*
X530195D01*
G01X532319Y-343150D02*
X532699Y-343567D01*
X533142Y-343817D01*
X533712Y-343900D01*
X534282Y-343733D01*
X534725Y-343400D01*
X535042Y-342817D01*
X535105Y-342150D01*
X534979Y-341483D01*
X534662Y-341067D01*
X534219Y-340733D01*
X533775Y-340650D01*
X533332Y-340733D01*
X532762Y-341067D01*
X532952Y-338900D01*
X534662D01*
G01X542709Y-343900D02*
Y-338900D01*
X545115D01*
G01X544229Y-341317D02*
X542709D01*
G01X547429Y-343900D02*
X549012Y-338900D01*
X550595Y-343900D01*
G01X550025Y-342150D02*
X547999D01*
G01X552782Y-343900D02*
X555442Y-338900D01*
G01X552782D02*
X555442Y-343900D01*
G01X559212Y-344067D02*
X559085Y-343983D01*
Y-343817D01*
X559212Y-343733D01*
X559339Y-343817D01*
Y-343983D01*
X559212Y-344067D01*
G01Y-341817D02*
X559085Y-341733D01*
Y-341567D01*
X559212Y-341483D01*
X559339Y-341567D01*
Y-341733D01*
X559212Y-341817D01*
G01X563995Y-345567D02*
X563362Y-344733D01*
X563045Y-343900D01*
Y-340567D01*
X563362Y-339733D01*
X563995Y-338900D01*
G01X569412D02*
X568905Y-339067D01*
X568525Y-339483D01*
X568272Y-339983D01*
X568082Y-340650D01*
X568019Y-341400D01*
X568082Y-342150D01*
X568272Y-342817D01*
X568525Y-343317D01*
X568905Y-343733D01*
X569412Y-343900D01*
X569919Y-343733D01*
X570299Y-343317D01*
X570552Y-342817D01*
X570742Y-342150D01*
X570805Y-341400D01*
X570742Y-340650D01*
X570552Y-339983D01*
X570299Y-339483D01*
X569919Y-339067D01*
X569412Y-338900D01*
G01X573119Y-342900D02*
X573499Y-343483D01*
X574005Y-343817D01*
X574575Y-343900D01*
X575082Y-343817D01*
X575589Y-343400D01*
X575905Y-342900D01*
X575969Y-342400D01*
X575842Y-341817D01*
X575399Y-341400D01*
X574955Y-341233D01*
X574385D01*
G01X574955D02*
X575335Y-340983D01*
X575652Y-340567D01*
X575779Y-340067D01*
X575652Y-339567D01*
X575335Y-339150D01*
X574765Y-338900D01*
X574195Y-338983D01*
X573625Y-339317D01*
G01X579929Y-345567D02*
X580562Y-344733D01*
X580879Y-343900D01*
Y-340567D01*
X580562Y-339733D01*
X579929Y-338900D01*
G01X583319Y-342900D02*
X583699Y-343483D01*
X584205Y-343817D01*
X584775Y-343900D01*
X585282Y-343817D01*
X585789Y-343400D01*
X586105Y-342900D01*
X586169Y-342400D01*
X586042Y-341817D01*
X585599Y-341400D01*
X585155Y-341233D01*
X584585D01*
G01X585155D02*
X585535Y-340983D01*
X585852Y-340567D01*
X585979Y-340067D01*
X585852Y-339567D01*
X585535Y-339150D01*
X584965Y-338900D01*
X584395Y-338983D01*
X583825Y-339317D01*
G01X588735Y-343317D02*
X589179Y-343733D01*
X589685Y-343900D01*
X590192Y-343733D01*
X590635Y-343233D01*
X590952Y-342483D01*
X591079Y-341733D01*
Y-340817D01*
X590952Y-340067D01*
X590635Y-339400D01*
X590255Y-339067D01*
X589812Y-338900D01*
X589305Y-339067D01*
X588925Y-339400D01*
X588672Y-339900D01*
X588545Y-340567D01*
X588672Y-341150D01*
X588989Y-341733D01*
X589369Y-342067D01*
X589812Y-342150D01*
X590319Y-341983D01*
X590699Y-341567D01*
X591079Y-340817D01*
G01X594785Y-343900D02*
X594912Y-342817D01*
X595102Y-341900D01*
X595355Y-341067D01*
X595672Y-340150D01*
X596179Y-338900D01*
X593645D01*
G01X599189Y-342233D02*
X600835D01*
G01X603719Y-342900D02*
X604099Y-343483D01*
X604605Y-343817D01*
X605175Y-343900D01*
X605682Y-343817D01*
X606189Y-343400D01*
X606505Y-342900D01*
X606569Y-342400D01*
X606442Y-341817D01*
X605999Y-341400D01*
X605555Y-341233D01*
X604985D01*
G01X605555D02*
X605935Y-340983D01*
X606252Y-340567D01*
X606379Y-340067D01*
X606252Y-339567D01*
X605935Y-339150D01*
X605365Y-338900D01*
X604795Y-338983D01*
X604225Y-339317D01*
G01X609009Y-341817D02*
X609452Y-341233D01*
X609832Y-340900D01*
X610339Y-340733D01*
X610782Y-340900D01*
X611099Y-341233D01*
X611352Y-341733D01*
X611415Y-342317D01*
X611352Y-342817D01*
X611099Y-343317D01*
X610719Y-343733D01*
X610275Y-343900D01*
X609769Y-343733D01*
X609325Y-343233D01*
X609072Y-342483D01*
X609009Y-341650D01*
X609135Y-340567D01*
X609325Y-339983D01*
X609642Y-339400D01*
X610085Y-338983D01*
X610529Y-338900D01*
X610972Y-339067D01*
X611289Y-339483D01*
G01X615312Y-343900D02*
Y-338900D01*
X614552Y-339900D01*
G01Y-343900D02*
X616072D01*
G01X621172D02*
Y-338900D01*
X618829Y-342483D01*
X621995D01*
G01X445212Y-273900D02*
Y-348900D01*
X945212D01*
Y-273900D01*
X445212D01*
G01X640212D02*
Y-348900D01*
G01Y-323900D02*
X743212D01*
Y-298900D01*
G01X640212D02*
X743212D01*
G01Y-273900D02*
Y-348900D01*
G01X745212Y-273900D02*
Y-348900D01*
G01X750719Y-333900D02*
Y-328900D01*
X751985D01*
X752492Y-329150D01*
X752872Y-329483D01*
X753189Y-329983D01*
X753442Y-330567D01*
X753505Y-331400D01*
X753442Y-332233D01*
X753189Y-332817D01*
X752872Y-333317D01*
X752492Y-333650D01*
X751985Y-333900D01*
X750719D01*
G01X755629D02*
X757212Y-328900D01*
X758795Y-333900D01*
G01X758225Y-332150D02*
X756199D01*
G01X762312Y-328900D02*
Y-333900D01*
G01X760855Y-328900D02*
X763769D01*
G01X768679Y-333900D02*
X766145D01*
Y-328900D01*
X768679D01*
G01X767665Y-331317D02*
X766145D01*
G01X772512Y-334067D02*
X772385Y-333983D01*
Y-333817D01*
X772512Y-333733D01*
X772639Y-333817D01*
Y-333983D01*
X772512Y-334067D01*
G01Y-331817D02*
X772385Y-331733D01*
Y-331567D01*
X772512Y-331483D01*
X772639Y-331567D01*
Y-331733D01*
X772512Y-331817D01*
G01X745212Y-323900D02*
X945212D01*
G01X750845Y-308900D02*
Y-303900D01*
X752365D01*
X752872Y-304150D01*
X753252Y-304733D01*
X753379Y-305400D01*
X753252Y-306067D01*
X752935Y-306567D01*
X752365Y-306817D01*
X750845D01*
G01X756072Y-309067D02*
X758352Y-303900D01*
G01X760855Y-308900D02*
Y-303900D01*
X763769Y-308900D01*
Y-303900D01*
G01X767412Y-309067D02*
X767285Y-308983D01*
Y-308817D01*
X767412Y-308733D01*
X767539Y-308817D01*
Y-308983D01*
X767412Y-309067D01*
G01Y-306817D02*
X767285Y-306733D01*
Y-306567D01*
X767412Y-306483D01*
X767539Y-306567D01*
Y-306733D01*
X767412Y-306817D01*
G01X745212Y-298900D02*
X945212D01*
G01X750845Y-283900D02*
Y-278900D01*
X752365D01*
X752872Y-279150D01*
X753252Y-279733D01*
X753379Y-280400D01*
X753252Y-281067D01*
X752935Y-281567D01*
X752365Y-281817D01*
X750845D01*
G01X755945Y-283900D02*
Y-278900D01*
X757529D01*
X758035Y-279150D01*
X758352Y-279483D01*
X758479Y-280150D01*
X758352Y-280817D01*
X757972Y-281233D01*
X757529Y-281483D01*
X755945D01*
G01X757529D02*
X758479Y-283900D01*
G01X762312D02*
X761805Y-283817D01*
X761362Y-283483D01*
X760982Y-282983D01*
X760729Y-282400D01*
X760602Y-281733D01*
Y-281067D01*
X760729Y-280400D01*
X760982Y-279817D01*
X761362Y-279317D01*
X761805Y-278983D01*
X762312Y-278900D01*
X762819Y-278983D01*
X763262Y-279317D01*
X763642Y-279817D01*
X763895Y-280400D01*
X764022Y-281067D01*
Y-281733D01*
X763895Y-282400D01*
X763642Y-282983D01*
X763262Y-283483D01*
X762819Y-283817D01*
X762312Y-283900D01*
G01X766145Y-282900D02*
X766462Y-283400D01*
X766842Y-283733D01*
X767285Y-283900D01*
X767792Y-283733D01*
X768172Y-283400D01*
X768552Y-282900D01*
X768679Y-282233D01*
Y-278900D01*
G01X773779Y-283900D02*
X771245D01*
Y-278900D01*
X773779D01*
G01X772765Y-281317D02*
X771245D01*
G01X779005Y-279317D02*
X778625Y-279067D01*
X778182Y-278900D01*
X777675D01*
X777105Y-279150D01*
X776662Y-279567D01*
X776345Y-280067D01*
X776092Y-280900D01*
X776029Y-281650D01*
X776155Y-282400D01*
X776345Y-282900D01*
X776725Y-283400D01*
X777169Y-283733D01*
X777612Y-283900D01*
X778055D01*
X778499Y-283733D01*
X778879Y-283483D01*
X779195Y-283150D01*
G01X782712Y-278900D02*
Y-283900D01*
G01X781255Y-278900D02*
X784169D01*
G01X787812Y-284067D02*
X787685Y-283983D01*
Y-283817D01*
X787812Y-283733D01*
X787939Y-283817D01*
Y-283983D01*
X787812Y-284067D01*
G01Y-281817D02*
X787685Y-281733D01*
Y-281567D01*
X787812Y-281483D01*
X787939Y-281567D01*
Y-281733D01*
X787812Y-281817D01*
G01X860212Y-323900D02*
Y-348900D01*
G01X865845Y-333900D02*
Y-328900D01*
X867429D01*
X867935Y-329150D01*
X868252Y-329483D01*
X868379Y-330150D01*
X868252Y-330817D01*
X867872Y-331233D01*
X867429Y-331483D01*
X865845D01*
G01X867429D02*
X868379Y-333900D01*
G01X873479D02*
X870945D01*
Y-328900D01*
X873479D01*
G01X872465Y-331317D02*
X870945D01*
G01X875729Y-328900D02*
X877312Y-333900D01*
X878895Y-328900D01*
G01X882412Y-334067D02*
X882285Y-333983D01*
Y-333817D01*
X882412Y-333733D01*
X882539Y-333817D01*
Y-333983D01*
X882412Y-334067D01*
G01Y-331817D02*
X882285Y-331733D01*
Y-331567D01*
X882412Y-331483D01*
X882539Y-331567D01*
Y-331733D01*
X882412Y-331817D01*
G01X909212Y-323900D02*
Y-348900D01*
G01X-471400Y-391900D02*
Y1528800D01*
X2244200D01*
Y-391900D01*
X-471400D01*
G01X455917Y-335560D02*
X456544Y-336085D01*
X457249Y-336400D01*
X457875D01*
X458502Y-336085D01*
X458972Y-335560D01*
X459207Y-334825D01*
X459050Y-334090D01*
X458659Y-333460D01*
X457954Y-333040D01*
X457014Y-332830D01*
X456465Y-332410D01*
X456230Y-331675D01*
X456387Y-330940D01*
X456779Y-330415D01*
X457327Y-330100D01*
X457875D01*
X458424Y-330310D01*
X458894Y-330835D01*
G01X462217Y-336400D02*
Y-330100D01*
G01X465507D02*
Y-336400D01*
G01Y-333250D02*
X462217D01*
G01X469222Y-330100D02*
X471102D01*
G01X470162D02*
Y-336400D01*
G01X469222D02*
X471102D01*
G01X478029D02*
X474895D01*
Y-330100D01*
X478029D01*
G01X476775Y-333145D02*
X474895D01*
G01X480960Y-336400D02*
Y-330100D01*
X484564Y-336400D01*
Y-330100D01*
G01X488905Y-337555D02*
X489219Y-336190D01*
G01X495362Y-330100D02*
Y-336400D01*
G01X493560Y-330100D02*
X497164D01*
G01X499704Y-336400D02*
X501662Y-330100D01*
X503620Y-336400D01*
G01X502915Y-334195D02*
X500409D01*
G01X507022Y-330100D02*
X508902D01*
G01X507962D02*
Y-336400D01*
G01X507022D02*
X508902D01*
G01X511912Y-330100D02*
X513009Y-336400D01*
X514262Y-330100D01*
X515515Y-336400D01*
X516612Y-330100D01*
G01X518604Y-336400D02*
X520562Y-330100D01*
X522520Y-336400D01*
G01X521815Y-334195D02*
X519309D01*
G01X525060Y-336400D02*
Y-330100D01*
X528664Y-336400D01*
Y-330100D01*
G01X537895Y-336400D02*
Y-330100D01*
X539854D01*
X540480Y-330415D01*
X540872Y-330835D01*
X541029Y-331675D01*
X540872Y-332515D01*
X540402Y-333040D01*
X539854Y-333355D01*
X537895D01*
G01X539854D02*
X541029Y-336400D01*
G01X545762Y-336610D02*
X545605Y-336505D01*
Y-336295D01*
X545762Y-336190D01*
X545919Y-336295D01*
Y-336505D01*
X545762Y-336610D01*
G01X552062Y-336400D02*
X551435Y-336295D01*
X550887Y-335875D01*
X550417Y-335245D01*
X550104Y-334510D01*
X549947Y-333670D01*
Y-332830D01*
X550104Y-331990D01*
X550417Y-331255D01*
X550887Y-330625D01*
X551435Y-330205D01*
X552062Y-330100D01*
X552689Y-330205D01*
X553237Y-330625D01*
X553707Y-331255D01*
X554020Y-331990D01*
X554177Y-332830D01*
Y-333670D01*
X554020Y-334510D01*
X553707Y-335245D01*
X553237Y-335875D01*
X552689Y-336295D01*
X552062Y-336400D01*
G01X558362Y-336610D02*
X558205Y-336505D01*
Y-336295D01*
X558362Y-336190D01*
X558519Y-336295D01*
Y-336505D01*
X558362Y-336610D01*
G01X566385Y-330625D02*
X565915Y-330310D01*
X565367Y-330100D01*
X564740D01*
X564035Y-330415D01*
X563487Y-330940D01*
X563095Y-331570D01*
X562782Y-332620D01*
X562704Y-333565D01*
X562860Y-334510D01*
X563095Y-335140D01*
X563565Y-335770D01*
X564114Y-336190D01*
X564662Y-336400D01*
X565210D01*
X565759Y-336190D01*
X566229Y-335875D01*
X566620Y-335455D01*
G01X570962Y-336610D02*
X570805Y-336505D01*
Y-336295D01*
X570962Y-336190D01*
X571119Y-336295D01*
Y-336505D01*
X570962Y-336610D01*
G01X455839Y-326400D02*
Y-320100D01*
G01X458815D02*
X455839Y-323985D01*
G01X459285Y-326400D02*
X457170Y-322200D01*
G01X462139Y-320100D02*
Y-324615D01*
X462452Y-325560D01*
X463079Y-326190D01*
X463862Y-326400D01*
X464645Y-326190D01*
X465272Y-325560D01*
X465585Y-324615D01*
Y-320100D01*
G01X471729Y-326400D02*
X468595D01*
Y-320100D01*
X471729D01*
G01X470475Y-323145D02*
X468595D01*
G01X475522Y-320100D02*
X477402D01*
G01X476462D02*
Y-326400D01*
G01X475522D02*
X477402D01*
G01X487417Y-325560D02*
X488044Y-326085D01*
X488749Y-326400D01*
X489375D01*
X490002Y-326085D01*
X490472Y-325560D01*
X490707Y-324825D01*
X490550Y-324090D01*
X490159Y-323460D01*
X489454Y-323040D01*
X488514Y-322830D01*
X487965Y-322410D01*
X487730Y-321675D01*
X487887Y-320940D01*
X488279Y-320415D01*
X488827Y-320100D01*
X489375D01*
X489924Y-320310D01*
X490394Y-320835D01*
G01X493717Y-326400D02*
Y-320100D01*
G01X497007D02*
Y-326400D01*
G01Y-323250D02*
X493717D01*
G01X499704Y-326400D02*
X501662Y-320100D01*
X503620Y-326400D01*
G01X502915Y-324195D02*
X500409D01*
G01X506160Y-326400D02*
Y-320100D01*
X509764Y-326400D01*
Y-320100D01*
G01X518917Y-326400D02*
Y-320100D01*
G01X522207D02*
Y-326400D01*
G01Y-323250D02*
X518917D01*
G01X525217Y-325560D02*
X525844Y-326085D01*
X526549Y-326400D01*
X527175D01*
X527802Y-326085D01*
X528272Y-325560D01*
X528507Y-324825D01*
X528350Y-324090D01*
X527959Y-323460D01*
X527254Y-323040D01*
X526314Y-322830D01*
X525765Y-322410D01*
X525530Y-321675D01*
X525687Y-320940D01*
X526079Y-320415D01*
X526627Y-320100D01*
X527175D01*
X527724Y-320310D01*
X528194Y-320835D01*
G01X532222Y-320100D02*
X534102D01*
G01X533162D02*
Y-326400D01*
G01X532222D02*
X534102D01*
G01X537504D02*
X539462Y-320100D01*
X541420Y-326400D01*
G01X540715Y-324195D02*
X538209D01*
G01X543960Y-326400D02*
Y-320100D01*
X547564Y-326400D01*
Y-320100D01*
G01X552532Y-323250D02*
X554099D01*
Y-325140D01*
X553629Y-325770D01*
X553080Y-326190D01*
X552297Y-326400D01*
X551514Y-326190D01*
X550965Y-325770D01*
X550495Y-325140D01*
X550182Y-324405D01*
X550025Y-323565D01*
Y-322830D01*
X550182Y-322200D01*
X550495Y-321465D01*
X550965Y-320835D01*
X551435Y-320415D01*
X552062Y-320100D01*
X552610D01*
X553237Y-320310D01*
X553707Y-320730D01*
G01X558205Y-327555D02*
X558519Y-326190D01*
G01X564662Y-320100D02*
Y-326400D01*
G01X562860Y-320100D02*
X566464D01*
G01X569004Y-326400D02*
X570962Y-320100D01*
X572920Y-326400D01*
G01X572215Y-324195D02*
X569709D01*
G01X577262Y-326400D02*
X576635Y-326295D01*
X576087Y-325875D01*
X575617Y-325245D01*
X575304Y-324510D01*
X575147Y-323670D01*
Y-322830D01*
X575304Y-321990D01*
X575617Y-321255D01*
X576087Y-320625D01*
X576635Y-320205D01*
X577262Y-320100D01*
X577889Y-320205D01*
X578437Y-320625D01*
X578907Y-321255D01*
X579220Y-321990D01*
X579377Y-322830D01*
Y-323670D01*
X579220Y-324510D01*
X578907Y-325245D01*
X578437Y-325875D01*
X577889Y-326295D01*
X577262Y-326400D01*
G01X589862D02*
Y-323565D01*
X588295Y-320100D01*
G01X591429D02*
X589862Y-323565D01*
G01X594439Y-320100D02*
Y-324615D01*
X594752Y-325560D01*
X595379Y-326190D01*
X596162Y-326400D01*
X596945Y-326190D01*
X597572Y-325560D01*
X597885Y-324615D01*
Y-320100D01*
G01X600504Y-326400D02*
X602462Y-320100D01*
X604420Y-326400D01*
G01X603715Y-324195D02*
X601209D01*
G01X606960Y-326400D02*
Y-320100D01*
X610564Y-326400D01*
Y-320100D01*
G01X455760Y-316400D02*
Y-310100D01*
X459364Y-316400D01*
Y-310100D01*
G01X463862Y-316400D02*
X463235Y-316295D01*
X462687Y-315875D01*
X462217Y-315245D01*
X461904Y-314510D01*
X461747Y-313670D01*
Y-312830D01*
X461904Y-311990D01*
X462217Y-311255D01*
X462687Y-310625D01*
X463235Y-310205D01*
X463862Y-310100D01*
X464489Y-310205D01*
X465037Y-310625D01*
X465507Y-311255D01*
X465820Y-311990D01*
X465977Y-312830D01*
Y-313670D01*
X465820Y-314510D01*
X465507Y-315245D01*
X465037Y-315875D01*
X464489Y-316295D01*
X463862Y-316400D01*
G01X470162Y-316610D02*
X470005Y-316505D01*
Y-316295D01*
X470162Y-316190D01*
X470319Y-316295D01*
Y-316505D01*
X470162Y-316610D01*
G01X476462Y-316400D02*
Y-310100D01*
X475522Y-311360D01*
G01Y-316400D02*
X477402D01*
G01X482762D02*
X483310Y-316295D01*
X483937Y-315980D01*
X484329Y-315455D01*
X484485Y-314720D01*
X484329Y-313985D01*
X483859Y-313355D01*
X483154Y-313040D01*
X482370D01*
X481900Y-312830D01*
X481509Y-312305D01*
X481352Y-311570D01*
X481587Y-310835D01*
X482135Y-310310D01*
X482762Y-310100D01*
X483389Y-310310D01*
X483937Y-310835D01*
X484172Y-311570D01*
X484015Y-312305D01*
X483624Y-312830D01*
X483154Y-313040D01*
X482370D01*
X481665Y-313355D01*
X481195Y-313985D01*
X481039Y-314720D01*
X481195Y-315455D01*
X481587Y-315980D01*
X482214Y-316295D01*
X482762Y-316400D01*
G01X489062D02*
X489610Y-316295D01*
X490237Y-315980D01*
X490629Y-315455D01*
X490785Y-314720D01*
X490629Y-313985D01*
X490159Y-313355D01*
X489454Y-313040D01*
X488670D01*
X488200Y-312830D01*
X487809Y-312305D01*
X487652Y-311570D01*
X487887Y-310835D01*
X488435Y-310310D01*
X489062Y-310100D01*
X489689Y-310310D01*
X490237Y-310835D01*
X490472Y-311570D01*
X490315Y-312305D01*
X489924Y-312830D01*
X489454Y-313040D01*
X488670D01*
X487965Y-313355D01*
X487495Y-313985D01*
X487339Y-314720D01*
X487495Y-315455D01*
X487887Y-315980D01*
X488514Y-316295D01*
X489062Y-316400D01*
G01X495205Y-317555D02*
X495519Y-316190D01*
G01X499312Y-310100D02*
X500409Y-316400D01*
X501662Y-310100D01*
X502915Y-316400D01*
X504012Y-310100D01*
G01X509529Y-316400D02*
X506395D01*
Y-310100D01*
X509529D01*
G01X508275Y-313145D02*
X506395D01*
G01X512460Y-316400D02*
Y-310100D01*
X516064Y-316400D01*
Y-310100D01*
G01X525217Y-316400D02*
Y-310100D01*
G01X528507D02*
Y-316400D01*
G01Y-313250D02*
X525217D01*
G01X530812Y-310100D02*
X531909Y-316400D01*
X533162Y-310100D01*
X534415Y-316400D01*
X535512Y-310100D01*
G01X537504Y-316400D02*
X539462Y-310100D01*
X541420Y-316400D01*
G01X540715Y-314195D02*
X538209D01*
G01X550574Y-311150D02*
X551044Y-310520D01*
X551592Y-310205D01*
X552219Y-310100D01*
X553002Y-310310D01*
X553550Y-310835D01*
X553707Y-311465D01*
X553629Y-312095D01*
X553315Y-312620D01*
X551749Y-313670D01*
X551044Y-314405D01*
X550574Y-315455D01*
X550417Y-316400D01*
X553707D01*
G01X556560D02*
Y-310100D01*
X560164Y-316400D01*
Y-310100D01*
G01X562939Y-316400D02*
Y-310100D01*
X564505D01*
X565132Y-310415D01*
X565602Y-310835D01*
X565994Y-311465D01*
X566307Y-312200D01*
X566385Y-313250D01*
X566307Y-314300D01*
X565994Y-315035D01*
X565602Y-315665D01*
X565132Y-316085D01*
X564505Y-316400D01*
X562939D01*
G01X575695D02*
Y-310100D01*
X577654D01*
X578280Y-310415D01*
X578672Y-310835D01*
X578829Y-311675D01*
X578672Y-312515D01*
X578202Y-313040D01*
X577654Y-313355D01*
X575695D01*
G01X577654D02*
X578829Y-316400D01*
G01X581839D02*
Y-310100D01*
X583405D01*
X584032Y-310415D01*
X584502Y-310835D01*
X584894Y-311465D01*
X585207Y-312200D01*
X585285Y-313250D01*
X585207Y-314300D01*
X584894Y-315035D01*
X584502Y-315665D01*
X584032Y-316085D01*
X583405Y-316400D01*
X581839D01*
G01X589862Y-316610D02*
X589705Y-316505D01*
Y-316295D01*
X589862Y-316190D01*
X590019Y-316295D01*
Y-316505D01*
X589862Y-316610D01*
G01X479862Y-303700D02*
X477342Y-303283D01*
X475137Y-301617D01*
X473247Y-299117D01*
X471987Y-296200D01*
X471357Y-292867D01*
Y-289533D01*
X471987Y-286200D01*
X473247Y-283283D01*
X475137Y-280784D01*
X477342Y-279117D01*
X479862Y-278700D01*
X482382Y-279117D01*
X484587Y-280784D01*
X486477Y-283283D01*
X487737Y-286200D01*
X488367Y-289533D01*
Y-292867D01*
X487737Y-296200D01*
X486477Y-299117D01*
X484587Y-301617D01*
X482382Y-303283D01*
X479862Y-303700D01*
G01X482382Y-297033D02*
X486162Y-303700D01*
G01X499707Y-287034D02*
Y-298700D01*
X500967Y-301617D01*
X502857Y-303283D01*
X505062Y-303700D01*
X507267Y-303283D01*
X509157Y-301617D01*
X510417Y-298700D01*
G01Y-303700D02*
Y-287034D01*
G01X535932Y-303700D02*
Y-287034D01*
G01Y-289950D02*
X534672Y-288284D01*
X532782Y-287450D01*
X530577Y-287034D01*
X528372Y-287867D01*
X526482Y-289533D01*
X525222Y-292034D01*
X524592Y-295367D01*
X525222Y-298700D01*
X526482Y-301201D01*
X528372Y-302867D01*
X530577Y-303700D01*
X532782Y-303283D01*
X534672Y-302034D01*
X535932Y-300367D01*
G01X550107Y-303700D02*
Y-287034D01*
G01Y-291200D02*
X551367Y-289117D01*
X553257Y-287450D01*
X555777Y-287034D01*
X557982Y-287450D01*
X559872Y-289117D01*
X560817Y-292034D01*
Y-303700D01*
G01X580662Y-278700D02*
Y-303700D01*
G01X576252Y-287034D02*
X585072D01*
G01X611532Y-303700D02*
Y-287034D01*
G01Y-289950D02*
X610272Y-288284D01*
X608382Y-287450D01*
X606177Y-287034D01*
X603972Y-287867D01*
X602082Y-289533D01*
X600822Y-292034D01*
X600192Y-295367D01*
X600822Y-298700D01*
X602082Y-301201D01*
X603972Y-302867D01*
X606177Y-303700D01*
X608382Y-303283D01*
X610272Y-302034D01*
X611532Y-300367D01*
G01X651212Y-283400D02*
Y-291400D01*
X655212D01*
G01X663012D02*
Y-286067D01*
G01Y-287000D02*
X662612Y-286467D01*
X662012Y-286200D01*
X661312Y-286067D01*
X660612Y-286333D01*
X660012Y-286867D01*
X659612Y-287667D01*
X659412Y-288733D01*
X659612Y-289800D01*
X660012Y-290600D01*
X660612Y-291133D01*
X661312Y-291400D01*
X662012Y-291267D01*
X662612Y-290867D01*
X663012Y-290334D01*
G01X667112Y-293800D02*
X667712Y-294067D01*
X668512Y-293800D01*
X669012Y-293267D01*
X669412Y-292600D01*
X670012Y-290467D01*
X671312Y-286067D01*
G01X668112D02*
X670012Y-290467D01*
G01X675712Y-287800D02*
X678912D01*
X678612Y-286867D01*
X678112Y-286333D01*
X677412Y-286067D01*
X676712Y-286200D01*
X676112Y-286600D01*
X675712Y-287533D01*
X675512Y-288334D01*
Y-289133D01*
X675712Y-289933D01*
X676212Y-290733D01*
X676812Y-291267D01*
X677512Y-291400D01*
X678212Y-291133D01*
X678912Y-290334D01*
G01X683812Y-291400D02*
Y-286067D01*
G01Y-287133D02*
X684312Y-286600D01*
X684812Y-286200D01*
X685512Y-286067D01*
X686012Y-286200D01*
X686612Y-286600D01*
G01X673512Y-333400D02*
X675912D01*
G01X674712D02*
Y-341400D01*
G01X673512D02*
X675912D01*
G01X681312D02*
Y-336067D01*
G01Y-337133D02*
X681812Y-336600D01*
X682312Y-336200D01*
X683012Y-336067D01*
X683512Y-336200D01*
X684112Y-336600D01*
G01X689212Y-337800D02*
X692412D01*
X692112Y-336867D01*
X691612Y-336333D01*
X690912Y-336067D01*
X690212Y-336200D01*
X689612Y-336600D01*
X689212Y-337533D01*
X689012Y-338334D01*
Y-339133D01*
X689212Y-339933D01*
X689712Y-340733D01*
X690312Y-341267D01*
X691012Y-341400D01*
X691712Y-341133D01*
X692412Y-340334D01*
G01X697012Y-341400D02*
Y-336067D01*
G01Y-337400D02*
X697412Y-336733D01*
X698012Y-336200D01*
X698812Y-336067D01*
X699512Y-336200D01*
X700112Y-336733D01*
X700412Y-337667D01*
Y-341400D01*
G01X705212Y-337800D02*
X708412D01*
X708112Y-336867D01*
X707612Y-336333D01*
X706912Y-336067D01*
X706212Y-336200D01*
X705612Y-336600D01*
X705212Y-337533D01*
X705012Y-338334D01*
Y-339133D01*
X705212Y-339933D01*
X705712Y-340733D01*
X706312Y-341267D01*
X707012Y-341400D01*
X707712Y-341133D01*
X708412Y-340334D01*
G01X682812Y-312400D02*
X684812D01*
Y-314800D01*
X684212Y-315600D01*
X683512Y-316133D01*
X682512Y-316400D01*
X681512Y-316133D01*
X680812Y-315600D01*
X680212Y-314800D01*
X679812Y-313867D01*
X679612Y-312800D01*
Y-311867D01*
X679812Y-311067D01*
X680212Y-310133D01*
X680812Y-309333D01*
X681412Y-308800D01*
X682212Y-308400D01*
X682912D01*
X683712Y-308667D01*
X684312Y-309200D01*
G01X687912Y-316400D02*
Y-308400D01*
X692512Y-316400D01*
Y-308400D01*
G01X696012Y-316400D02*
Y-308400D01*
X698012D01*
X698812Y-308800D01*
X699412Y-309333D01*
X699912Y-310133D01*
X700312Y-311067D01*
X700412Y-312400D01*
X700312Y-313733D01*
X699912Y-314667D01*
X699412Y-315467D01*
X698812Y-316000D01*
X698012Y-316400D01*
X696012D01*
G01X706212D02*
Y-308400D01*
X705012Y-310000D01*
G01Y-316400D02*
X707412D01*
G01X704512Y-291400D02*
X704712Y-289667D01*
X705012Y-288200D01*
X705412Y-286867D01*
X705912Y-285400D01*
X706712Y-283400D01*
X702712D01*
G01X777812Y-334733D02*
X778412Y-333933D01*
X779112Y-333533D01*
X779912Y-333400D01*
X780912Y-333667D01*
X781612Y-334333D01*
X781812Y-335133D01*
X781712Y-335934D01*
X781312Y-336600D01*
X779312Y-337933D01*
X778412Y-338867D01*
X777812Y-340200D01*
X777612Y-341400D01*
X781812D01*
G01X787712Y-333400D02*
X786912Y-333667D01*
X786312Y-334333D01*
X785912Y-335133D01*
X785612Y-336200D01*
X785512Y-337400D01*
X785612Y-338600D01*
X785912Y-339667D01*
X786312Y-340467D01*
X786912Y-341133D01*
X787712Y-341400D01*
X788512Y-341133D01*
X789112Y-340467D01*
X789512Y-339667D01*
X789812Y-338600D01*
X789912Y-337400D01*
X789812Y-336200D01*
X789512Y-335133D01*
X789112Y-334333D01*
X788512Y-333667D01*
X787712Y-333400D01*
G01X795712Y-341400D02*
Y-333400D01*
X794512Y-335000D01*
G01Y-341400D02*
X796912D01*
G01X801812Y-334733D02*
X802412Y-333933D01*
X803112Y-333533D01*
X803912Y-333400D01*
X804912Y-333667D01*
X805612Y-334333D01*
X805812Y-335133D01*
X805712Y-335934D01*
X805312Y-336600D01*
X803312Y-337933D01*
X802412Y-338867D01*
X801812Y-340200D01*
X801612Y-341400D01*
X805812D01*
G01X809912Y-341667D02*
X813512Y-333400D01*
G01X819712Y-341400D02*
Y-333400D01*
X818512Y-335000D01*
G01Y-341400D02*
X820912D01*
G01X827712Y-333400D02*
X826912Y-333667D01*
X826312Y-334333D01*
X825912Y-335133D01*
X825612Y-336200D01*
X825512Y-337400D01*
X825612Y-338600D01*
X825912Y-339667D01*
X826312Y-340467D01*
X826912Y-341133D01*
X827712Y-341400D01*
X828512Y-341133D01*
X829112Y-340467D01*
X829512Y-339667D01*
X829812Y-338600D01*
X829912Y-337400D01*
X829812Y-336200D01*
X829512Y-335133D01*
X829112Y-334333D01*
X828512Y-333667D01*
X827712Y-333400D01*
G01X833912Y-341667D02*
X837512Y-333400D01*
G01X841512Y-339800D02*
X842112Y-340733D01*
X842912Y-341267D01*
X843812Y-341400D01*
X844612Y-341267D01*
X845412Y-340600D01*
X845912Y-339800D01*
X846012Y-339000D01*
X845812Y-338067D01*
X845112Y-337400D01*
X844412Y-337133D01*
X843512D01*
G01X844412D02*
X845012Y-336733D01*
X845512Y-336067D01*
X845712Y-335267D01*
X845512Y-334467D01*
X845012Y-333800D01*
X844112Y-333400D01*
X843212Y-333533D01*
X842312Y-334067D01*
G01X851712Y-341400D02*
Y-333400D01*
X850512Y-335000D01*
G01Y-341400D02*
X852912D01*
G01X777512Y-316400D02*
Y-308400D01*
X779512D01*
X780312Y-308800D01*
X780912Y-309333D01*
X781412Y-310133D01*
X781812Y-311067D01*
X781912Y-312400D01*
X781812Y-313733D01*
X781412Y-314667D01*
X780912Y-315467D01*
X780312Y-316000D01*
X779512Y-316400D01*
X777512D01*
G01X785212D02*
X787712Y-308400D01*
X790212Y-316400D01*
G01X789312Y-313600D02*
X786112D01*
G01X795712Y-308400D02*
X794912Y-308667D01*
X794312Y-309333D01*
X793912Y-310133D01*
X793612Y-311200D01*
X793512Y-312400D01*
X793612Y-313600D01*
X793912Y-314667D01*
X794312Y-315467D01*
X794912Y-316133D01*
X795712Y-316400D01*
X796512Y-316133D01*
X797112Y-315467D01*
X797512Y-314667D01*
X797812Y-313600D01*
X797912Y-312400D01*
X797812Y-311200D01*
X797512Y-310133D01*
X797112Y-309333D01*
X796512Y-308667D01*
X795712Y-308400D01*
G01X803712D02*
Y-316400D01*
G01X801412Y-308400D02*
X806012D01*
G01X809812Y-313067D02*
X810512Y-312133D01*
X811112Y-311600D01*
X811912Y-311333D01*
X812612Y-311600D01*
X813112Y-312133D01*
X813512Y-312933D01*
X813612Y-313867D01*
X813512Y-314667D01*
X813112Y-315467D01*
X812512Y-316133D01*
X811812Y-316400D01*
X811012Y-316133D01*
X810312Y-315334D01*
X809912Y-314133D01*
X809812Y-312800D01*
X810012Y-311067D01*
X810312Y-310133D01*
X810812Y-309200D01*
X811512Y-308533D01*
X812212Y-308400D01*
X812912Y-308667D01*
X813412Y-309333D01*
G01X817112Y-316400D02*
Y-308400D01*
X819712Y-315067D01*
X822312Y-308400D01*
Y-316400D01*
G01X827712Y-308400D02*
Y-316400D01*
G01X825412Y-308400D02*
X830012D01*
G01X833612Y-316400D02*
Y-308400D01*
G01X837812D02*
Y-316400D01*
G01Y-312400D02*
X833612D01*
G01X843712Y-316400D02*
X844412Y-316267D01*
X845212Y-315867D01*
X845712Y-315200D01*
X845912Y-314267D01*
X845712Y-313334D01*
X845112Y-312533D01*
X844212Y-312133D01*
X843212D01*
X842612Y-311867D01*
X842112Y-311200D01*
X841912Y-310267D01*
X842212Y-309333D01*
X842912Y-308667D01*
X843712Y-308400D01*
X844512Y-308667D01*
X845212Y-309333D01*
X845512Y-310267D01*
X845312Y-311200D01*
X844812Y-311867D01*
X844212Y-312133D01*
X843212D01*
X842312Y-312533D01*
X841712Y-313334D01*
X841512Y-314267D01*
X841712Y-315200D01*
X842212Y-315867D01*
X843012Y-316267D01*
X843712Y-316400D01*
G01X853912Y-309067D02*
X853312Y-308667D01*
X852612Y-308400D01*
X851812D01*
X850912Y-308800D01*
X850212Y-309467D01*
X849712Y-310267D01*
X849312Y-311600D01*
X849212Y-312800D01*
X849412Y-314000D01*
X849712Y-314800D01*
X850312Y-315600D01*
X851012Y-316133D01*
X851712Y-316400D01*
X852412D01*
X853112Y-316133D01*
X853712Y-315733D01*
X854212Y-315200D01*
G01X859712Y-308400D02*
X858912Y-308667D01*
X858312Y-309333D01*
X857912Y-310133D01*
X857612Y-311200D01*
X857512Y-312400D01*
X857612Y-313600D01*
X857912Y-314667D01*
X858312Y-315467D01*
X858912Y-316133D01*
X859712Y-316400D01*
X860512Y-316133D01*
X861112Y-315467D01*
X861512Y-314667D01*
X861812Y-313600D01*
X861912Y-312400D01*
X861812Y-311200D01*
X861512Y-310133D01*
X861112Y-309333D01*
X860512Y-308667D01*
X859712Y-308400D01*
G01X799712Y-283400D02*
Y-291400D01*
G01X797412Y-283400D02*
X802012D01*
G01X805812Y-288067D02*
X806512Y-287133D01*
X807112Y-286600D01*
X807912Y-286333D01*
X808612Y-286600D01*
X809112Y-287133D01*
X809512Y-287933D01*
X809612Y-288867D01*
X809512Y-289667D01*
X809112Y-290467D01*
X808512Y-291133D01*
X807812Y-291400D01*
X807012Y-291133D01*
X806312Y-290334D01*
X805912Y-289133D01*
X805812Y-287800D01*
X806012Y-286067D01*
X806312Y-285133D01*
X806812Y-284200D01*
X807512Y-283533D01*
X808212Y-283400D01*
X808912Y-283667D01*
X809412Y-284333D01*
G01X813112Y-291400D02*
Y-283400D01*
X815712Y-290067D01*
X818312Y-283400D01*
Y-291400D01*
G01X820712Y-294067D02*
X826712D01*
G01X831712Y-283400D02*
Y-291400D01*
G01X829412Y-283400D02*
X834012D01*
G01X838312Y-291400D02*
Y-286067D01*
G01Y-287133D02*
X838812Y-286600D01*
X839312Y-286200D01*
X840012Y-286067D01*
X840512Y-286200D01*
X841112Y-286600D01*
G01X849512Y-291400D02*
Y-286067D01*
G01Y-287000D02*
X849112Y-286467D01*
X848512Y-286200D01*
X847812Y-286067D01*
X847112Y-286333D01*
X846512Y-286867D01*
X846112Y-287667D01*
X845912Y-288733D01*
X846112Y-289800D01*
X846512Y-290600D01*
X847112Y-291133D01*
X847812Y-291400D01*
X848512Y-291267D01*
X849112Y-290867D01*
X849512Y-290334D01*
G01X853612Y-293800D02*
X854212Y-294067D01*
X855012Y-293800D01*
X855512Y-293267D01*
X855912Y-292600D01*
X856512Y-290467D01*
X857812Y-286067D01*
G01X854612D02*
X856512Y-290467D01*
G01X860712Y-294067D02*
X866712D01*
G01X872512Y-287133D02*
X872912Y-286733D01*
X873212Y-286067D01*
X873412Y-285133D01*
X873212Y-284333D01*
X872812Y-283800D01*
X872112Y-283400D01*
X869412D01*
Y-291400D01*
X872712D01*
X873412Y-290867D01*
X873812Y-290067D01*
X874012Y-289133D01*
X873812Y-288200D01*
X873212Y-287400D01*
X872512Y-287133D01*
X869412D01*
G01X877712Y-291400D02*
Y-283400D01*
X880112D01*
X880912Y-283800D01*
X881512Y-284733D01*
X881712Y-285800D01*
X881512Y-286867D01*
X881012Y-287667D01*
X880112Y-288067D01*
X877712D01*
G01X896912Y-334067D02*
X896312Y-333667D01*
X895612Y-333400D01*
X894812D01*
X893912Y-333800D01*
X893212Y-334467D01*
X892712Y-335267D01*
X892312Y-336600D01*
X892212Y-337800D01*
X892412Y-339000D01*
X892712Y-339800D01*
X893312Y-340600D01*
X894012Y-341133D01*
X894712Y-341400D01*
X895412D01*
X896112Y-341133D01*
X896712Y-340733D01*
X897212Y-340200D01*
G01X922212Y-341400D02*
Y-333400D01*
X921012Y-335000D01*
G01Y-341400D02*
X923412D01*
G01X928312Y-338067D02*
X929012Y-337133D01*
X929612Y-336600D01*
X930412Y-336333D01*
X931112Y-336600D01*
X931612Y-337133D01*
X932012Y-337933D01*
X932112Y-338867D01*
X932012Y-339667D01*
X931612Y-340467D01*
X931012Y-341133D01*
X930312Y-341400D01*
X929512Y-341133D01*
X928812Y-340334D01*
X928412Y-339133D01*
X928312Y-337800D01*
X928512Y-336067D01*
X928812Y-335133D01*
X929312Y-334200D01*
X930012Y-333533D01*
X930712Y-333400D01*
X931412Y-333667D01*
X931912Y-334333D01*
M02*
